FILE_TYPE = MACRO_DRAWING;
SET COLOR_WIRE YELLOW;
SET COLOR_PROP MONO;
SET COLOR_DOT WHITE;
SET COLOR_ARC YELLOW;
SET COLOR_BODY GREEN;
SET COLOR_NOTE MONO;
SET PROP_DISPLAY VALUE;
SET PAGE_NUMBER P211;
FORCEADD CAP_A..1
(2475 1425);
FORCEPROP 1 LASTPIN (2475 1325) $PN 2
J 0
(2485 1305);
DISPLAY 0.617021 (2485 1305);
PAINT ORANGE (2485 1305);
FORCEPROP 1 LASTPIN (2475 1525) $PN 1
J 0
(2485 1505);
DISPLAY 0.617021 (2485 1505);
PAINT ORANGE (2485 1505);
FORCEPROP 1 LAST MATERIAL X6S
J 0
(2525 1325);
DISPLAY 0.617021 (2525 1325);
PAINT SKYBLUE (2525 1325);
FORCEPROP 1 LAST VOLTAGE 6.3V
J 0
(2525 1425);
DISPLAY 0.617021 (2525 1425);
PAINT SKYBLUE (2525 1425);
FORCEPROP 1 LAST PACK_TYPE 0402V
J 0
(2525 1225);
DISPLAY 0.617021 (2525 1225);
PAINT SKYBLUE (2525 1225);
FORCEPROP 1 LAST TOLERANCE 10%
J 0
(2525 1375);
DISPLAY 0.617021 (2525 1375);
PAINT SKYBLUE (2525 1375);
FORCEPROP 1 LAST VALUE 1.0UF
J 0
(2525 1475);
DISPLAY 0.617021 (2525 1475);
PAINT SKYBLUE (2525 1475);
FORCEPROP 1 LAST PART_NUMBER D97712-004
J 0
(2525 1275);
DISPLAY 0.617021 (2525 1275);
PAINT BLUE (2525 1275);
FORCEPROP 1 LAST LOCATION C3P4
J 0
(2525 1525);
DISPLAY 0.617021 (2525 1525);
PAINT AQUA (2525 1525);
FORCEPROP 2 LAST CDS_LIB dev_discrete
J 0
(2475 1425);
PAINT ORANGE (2475 1425);
DISPLAY INVISIBLE (2475 1425);
FORCEPROP 2 LAST CDS_LOCATION C3P4
J 0
(2525 1525);
DISPLAY 0.617021 (2525 1525);
PAINT AQUA (2525 1525);
DISPLAY INVISIBLE (2525 1525);
FORCEPROP 2 LAST CDS_SEC 1
J 0
(2525 1575);
PAINT ORANGE (2525 1575);
DISPLAY INVISIBLE (2525 1575);
FORCEPROP 2 LAST SEC_TYPE 0402V
J 0
(2525 1625);
DISPLAY 1.021277 (2525 1625);
PAINT ORANGE (2525 1625);
DISPLAY INVISIBLE (2525 1625);
FORCEPROP 2 LAST SEC 1
J 0
(2525 1625);
DISPLAY 0.680851 (2525 1625);
PAINT MONO (2525 1625);
DISPLAY INVISIBLE (2525 1625);
FORCEPROP 1 LAST PATH I11
J 0
(2525 1575);
DISPLAY 0.978723 (2525 1575);
PAINT WHITE (2525 1575);
DISPLAY INVISIBLE (2525 1575);
FORCEPROP 2 LAST ROOM PVCCIO_CPU0
J 0
(2525 1575);
DISPLAY 1.361702 (2525 1575);
PAINT ORANGE (2525 1575);
DISPLAY INVISIBLE (2525 1575);
FORCEADD GND..1
(2475 1100);
FORCEPROP 3 LASTPIN (2475 1150) SIG_NAME GND\g
J 0
(2485 1160);
DISPLAY 0.659574 (2485 1160);
PAINT MONO (2485 1160);
DISPLAY INVISIBLE (2485 1160);
FORCEPROP 2 LAST ROOM PVCCIO_CPU0
J 0
(1900 1175);
DISPLAY 1.361702 (1900 1175);
PAINT ORANGE (1900 1175);
DISPLAY INVISIBLE (1900 1175);
FORCEPROP 1 LAST PATH I12
J 0
(2550 1100);
DISPLAY 0.872340 (2550 1100);
PAINT AQUA (2550 1100);
DISPLAY INVISIBLE (2550 1100);
FORCEPROP 2 LAST CDS_LIB mstr_symbols
J 0
(2475 1100);
PAINT ORANGE (2475 1100);
DISPLAY INVISIBLE (2475 1100);
FORCEPROP 1 LAST SIZE 1B
J 0
(2550 1050);
DISPLAY 1.170213 (2550 1050);
PAINT AQUA (2550 1050);
DISPLAY INVISIBLE (2550 1050);
FORCEPROP 1 LAST VOLTAGE 0
J 0
(2475 1100);
PAINT SKYBLUE (2475 1100);
DISPLAY INVISIBLE (2475 1100);
FORCEPROP 1 LAST BODY_TYPE PLUMBING
J 0
(2430 1057);
DISPLAY 0.340426 (2430 1057);
PAINT GREEN (2430 1057);
DISPLAY INVISIBLE (2430 1057);
FORCEPROP 1 LAST HDL_POWER GND
J 0
(2475 1250);
DISPLAY 1.170213 (2475 1250);
PAINT GREEN (2475 1250);
DISPLAY INVISIBLE (2475 1250);
FORCEADD CAP_A..1
(2075 1425);
FORCEPROP 1 LAST PACK_TYPE 0402V
J 0
(2125 1225);
DISPLAY 0.617021 (2125 1225);
PAINT SKYBLUE (2125 1225);
FORCEPROP 1 LASTPIN (2075 1325) $PN 2
J 0
(2085 1305);
DISPLAY 0.617021 (2085 1305);
PAINT ORANGE (2085 1305);
FORCEPROP 1 LASTPIN (2075 1525) $PN 1
J 0
(2085 1505);
DISPLAY 0.617021 (2085 1505);
PAINT ORANGE (2085 1505);
FORCEPROP 1 LAST MATERIAL X7R
J 0
(2125 1325);
DISPLAY 0.617021 (2125 1325);
PAINT SKYBLUE (2125 1325);
FORCEPROP 1 LAST VOLTAGE 16V
J 0
(2125 1425);
DISPLAY 0.617021 (2125 1425);
PAINT SKYBLUE (2125 1425);
FORCEPROP 1 LAST TOLERANCE 10%
J 0
(2125 1375);
DISPLAY 0.617021 (2125 1375);
PAINT SKYBLUE (2125 1375);
FORCEPROP 1 LAST VALUE 0.1UF
J 0
(2125 1475);
DISPLAY 0.617021 (2125 1475);
PAINT SKYBLUE (2125 1475);
FORCEPROP 1 LAST PART_NUMBER A36096-030
J 0
(2125 1275);
DISPLAY 0.617021 (2125 1275);
PAINT BLUE (2125 1275);
FORCEPROP 1 LAST LOCATION C3P5
J 0
(2125 1525);
DISPLAY 0.617021 (2125 1525);
PAINT AQUA (2125 1525);
FORCEPROP 2 LAST CDS_LIB dev_discrete
J 0
(2075 1425);
PAINT ORANGE (2075 1425);
DISPLAY INVISIBLE (2075 1425);
FORCEPROP 2 LAST CDS_LOCATION C3P5
J 0
(2125 1525);
DISPLAY 0.617021 (2125 1525);
PAINT AQUA (2125 1525);
DISPLAY INVISIBLE (2125 1525);
FORCEPROP 1 LAST PATH I13
J 0
(2125 1575);
DISPLAY 0.978723 (2125 1575);
PAINT WHITE (2125 1575);
DISPLAY INVISIBLE (2125 1575);
FORCEPROP 2 LAST ROOM PVCCIO_CPU0
J 0
(2125 1575);
DISPLAY 1.361702 (2125 1575);
PAINT ORANGE (2125 1575);
DISPLAY INVISIBLE (2125 1575);
FORCEPROP 2 LAST CDS_SEC 1
J 0
(2125 1575);
PAINT ORANGE (2125 1575);
DISPLAY INVISIBLE (2125 1575);
FORCEPROP 2 LAST SEC_TYPE 0402V
J 0
(2125 1650);
DISPLAY 1.021277 (2125 1650);
PAINT ORANGE (2125 1650);
DISPLAY INVISIBLE (2125 1650);
FORCEPROP 2 LAST SEC 1
J 0
(2125 1650);
DISPLAY 0.680851 (2125 1650);
PAINT MONO (2125 1650);
DISPLAY INVISIBLE (2125 1650);
FORCEADD GND..1
(2075 1225);
FORCEPROP 3 LASTPIN (2075 1275) SIG_NAME GND\g
J 0
(2085 1285);
DISPLAY 0.659574 (2085 1285);
PAINT MONO (2085 1285);
DISPLAY INVISIBLE (2085 1285);
FORCEPROP 2 LAST ROOM PVCCIO_CPU0
J 0
(1500 1300);
DISPLAY 1.361702 (1500 1300);
PAINT ORANGE (1500 1300);
DISPLAY INVISIBLE (1500 1300);
FORCEPROP 1 LAST PATH I14
J 0
(2150 1225);
DISPLAY 0.872340 (2150 1225);
PAINT AQUA (2150 1225);
DISPLAY INVISIBLE (2150 1225);
FORCEPROP 1 LAST VOLTAGE 0
J 0
(2075 1225);
PAINT SKYBLUE (2075 1225);
DISPLAY INVISIBLE (2075 1225);
FORCEPROP 1 LAST SIZE 1B
J 0
(2150 1175);
DISPLAY 1.170213 (2150 1175);
PAINT AQUA (2150 1175);
DISPLAY INVISIBLE (2150 1175);
FORCEPROP 2 LAST CDS_LIB mstr_symbols
J 0
(2075 1225);
PAINT ORANGE (2075 1225);
DISPLAY INVISIBLE (2075 1225);
FORCEPROP 1 LAST BODY_TYPE PLUMBING
J 0
(2030 1182);
DISPLAY 0.340426 (2030 1182);
PAINT GREEN (2030 1182);
DISPLAY INVISIBLE (2030 1182);
FORCEPROP 1 LAST HDL_POWER GND
J 0
(2075 1375);
DISPLAY 1.170213 (2075 1375);
PAINT GREEN (2075 1375);
DISPLAY INVISIBLE (2075 1375);
FORCEADD OFFPAGE..2
R 2
(-2750 3000);
FORCEPROP 2 LAST $XR0 211 
J 0
(-3035 3000);
DISPLAY 0.638298 (-3035 3000);
PAINT MONO (-3035 3000);
FORCEPROP 2 LAST ROOM PVCCIO_CPU0
J 0
(-3300 3075);
DISPLAY 1.361702 (-3300 3075);
PAINT ORANGE (-3300 3075);
DISPLAY INVISIBLE (-3300 3075);
FORCEPROP 2 LAST CDS_LIB mstr_standard
J 0
(-2750 3000);
PAINT ORANGE (-2750 3000);
DISPLAY INVISIBLE (-2750 3000);
FORCEPROP 2 LAST PATH I15
J 0
(-2700 3075);
DISPLAY 1.021277 (-2700 3075);
PAINT ORANGE (-2700 3075);
DISPLAY INVISIBLE (-2700 3075);
FORCEPROP 1 LAST OFFPAGE TRUE
J 2
(-3075 2875);
DISPLAY 1.170213 (-3075 2875);
PAINT GREEN (-3075 2875);
DISPLAY INVISIBLE (-3075 2875);
FORCEPROP 1 LAST COMMENT_BODY TRUE
J 2
(-2705 2905);
DISPLAY 1.170213 (-2705 2905);
PAINT GREEN (-2705 2905);
DISPLAY INVISIBLE (-2705 2905);
FORCEADD RES..1
(-1250 2950);
FORCEPROP 1 LASTPIN (-1350 2950) $PN 1
J 0
(-1338 2962);
DISPLAY 0.617021 (-1338 2962);
PAINT ORANGE (-1338 2962);
FORCEPROP 1 LAST VALUE 0.0
J 2
(-1350 2850);
DISPLAY 0.617021 (-1350 2850);
PAINT SKYBLUE (-1350 2850);
FORCEPROP 1 LAST WATTAGE 1/16W
J 2
(-1275 2800);
DISPLAY 0.617021 (-1275 2800);
PAINT SKYBLUE (-1275 2800);
FORCEPROP 1 LAST TOLERANCE 5%
J 0
(-1300 2850);
DISPLAY 0.617021 (-1300 2850);
PAINT SKYBLUE (-1300 2850);
FORCEPROP 1 LAST PART_NUMBER G21497-005
J 0
(-1400 2900);
DISPLAY 0.617021 (-1400 2900);
PAINT BLUE (-1400 2900);
FORCEPROP 1 LAST LOCATION R3P11
J 0
(-1300 3000);
DISPLAY 0.617021 (-1300 3000);
PAINT AQUA (-1300 3000);
FORCEPROP 1 LASTPIN (-1150 2950) $PN 2
J 0
(-1188 2962);
DISPLAY 0.617021 (-1188 2962);
PAINT ORANGE (-1188 2962);
FORCEPROP 1 LAST MATERIAL CHIP
J 0
(-1250 2800);
DISPLAY 0.617021 (-1250 2800);
PAINT SKYBLUE (-1250 2800);
FORCEPROP 1 LAST PACK_TYPE 0402
J 0
(-1175 2850);
DISPLAY 0.617021 (-1175 2850);
PAINT SKYBLUE (-1175 2850);
FORCEPROP 2 LAST CDS_LOCATION R3P11
J 0
(-1300 3000);
DISPLAY 0.617021 (-1300 3000);
PAINT AQUA (-1300 3000);
DISPLAY INVISIBLE (-1300 3000);
FORCEPROP 2 LAST CDS_LIB mstr_discrete
J 0
(-1250 2950);
PAINT ORANGE (-1250 2950);
DISPLAY INVISIBLE (-1250 2950);
FORCEPROP 2 LAST ROOM PVCCIO_CPU0
J 0
(-1300 3050);
DISPLAY 1.361702 (-1300 3050);
PAINT ORANGE (-1300 3050);
DISPLAY INVISIBLE (-1300 3050);
FORCEPROP 0 LAST SEC 1
J 0
(-1300 3050);
DISPLAY 0.680851 (-1300 3050);
PAINT MONO (-1300 3050);
DISPLAY INVISIBLE (-1300 3050);
FORCEPROP 1 LAST PATH I16
J 0
(-1300 3100);
DISPLAY 0.978723 (-1300 3100);
PAINT WHITE (-1300 3100);
DISPLAY INVISIBLE (-1300 3100);
FORCEPROP 2 LAST SEC_TYPE 0402
J 0
(-1300 3150);
DISPLAY 1.021277 (-1300 3150);
PAINT ORANGE (-1300 3150);
DISPLAY INVISIBLE (-1300 3150);
FORCEADD RES..2
(-1675 4500);
FORCEPROP 1 LASTPIN (-1675 4600) $PN 1
J 0
(-1670 4562);
DISPLAY 0.617021 (-1670 4562);
PAINT ORANGE (-1670 4562);
FORCEPROP 1 LASTPIN (-1675 4400) $PN 2
J 0
(-1670 4410);
DISPLAY 0.617021 (-1670 4410);
PAINT ORANGE (-1670 4410);
FORCEPROP 1 LAST TOLERANCE 1%
J 0
(-1630 4525);
DISPLAY 0.617021 (-1630 4525);
PAINT SKYBLUE (-1630 4525);
FORCEPROP 1 LAST WATTAGE 1/16W
J 0
(-1635 4475);
DISPLAY 0.617021 (-1635 4475);
PAINT SKYBLUE (-1635 4475);
FORCEPROP 1 LAST PACK_TYPE 0402
J 0
(-1635 4325);
DISPLAY 0.617021 (-1635 4325);
PAINT SKYBLUE (-1635 4325);
FORCEPROP 1 LAST VALUE 100.0
J 0
(-1630 4575);
DISPLAY 0.617021 (-1630 4575);
PAINT SKYBLUE (-1630 4575);
FORCEPROP 1 LAST PART_NUMBER G21796-017
J 0
(-1635 4375);
DISPLAY 0.617021 (-1635 4375);
PAINT BLUE (-1635 4375);
FORCEPROP 1 LAST LOCATION R3P13
J 0
(-1630 4625);
DISPLAY 0.617021 (-1630 4625);
PAINT AQUA (-1630 4625);
FORCEPROP 1 LAST MATERIAL EMPTY
J 0
(-1635 4425);
DISPLAY 0.617021 (-1635 4425);
PAINT RED (-1635 4425);
FORCEPROP 2 LAST CDS_LIB mstr_discrete
J 0
(-1675 4500);
PAINT ORANGE (-1675 4500);
DISPLAY INVISIBLE (-1675 4500);
FORCEPROP 2 LAST ROOM PVCCIO_CPU0
J 0
(-1625 4675);
DISPLAY 1.361702 (-1625 4675);
PAINT ORANGE (-1625 4675);
DISPLAY INVISIBLE (-1625 4675);
FORCEPROP 1 LAST PATH I17
J 0
(-1625 4675);
DISPLAY 0.978723 (-1625 4675);
PAINT WHITE (-1625 4675);
DISPLAY INVISIBLE (-1625 4675);
FORCEPROP 2 LAST CDS_LOCATION R3P13
J 0
(-1630 4625);
DISPLAY 0.617021 (-1630 4625);
PAINT AQUA (-1630 4625);
DISPLAY INVISIBLE (-1630 4625);
FORCEPROP 0 LAST SEC 1
J 0
(-1625 4675);
DISPLAY 0.680851 (-1625 4675);
PAINT MONO (-1625 4675);
DISPLAY INVISIBLE (-1625 4675);
FORCEPROP 2 LAST SEC_TYPE 0402
J 0
(-1625 4725);
DISPLAY 1.021277 (-1625 4725);
PAINT ORANGE (-1625 4725);
DISPLAY INVISIBLE (-1625 4725);
FORCEADD PVCCIO_CPU0..1
(-1675 4825);
FORCEPROP 3 LASTPIN (-1675 4775) SIG_NAME PVCCIO_CPU0\g
J 0
(-1665 4785);
DISPLAY 0.659574 (-1665 4785);
PAINT MONO (-1665 4785);
DISPLAY INVISIBLE (-1665 4785);
FORCEPROP 1 LAST PATH I18
J 0
(-1625 4850);
DISPLAY 0.872340 (-1625 4850);
PAINT AQUA (-1625 4850);
DISPLAY INVISIBLE (-1625 4850);
FORCEPROP 2 LAST CDS_LIB mstr_symbols
J 0
(-1675 4825);
PAINT ORANGE (-1675 4825);
DISPLAY INVISIBLE (-1675 4825);
FORCEPROP 1 LAST VOLTAGE 1.1V
J 0
(-1720 4782);
DISPLAY 0.340426 (-1720 4782);
PAINT SKYBLUE (-1720 4782);
DISPLAY INVISIBLE (-1720 4782);
FORCEPROP 1 LAST BODY_TYPE PLUMBING
J 0
(-1720 4782);
DISPLAY 0.340426 (-1720 4782);
PAINT GREEN (-1720 4782);
DISPLAY INVISIBLE (-1720 4782);
FORCEPROP 1 LAST HDL_POWER PVCCIO_CPU0
J 1
(-1675 4875);
DISPLAY 0.872340 (-1675 4875);
PAINT GREEN (-1675 4875);
DISPLAY INVISIBLE (-1675 4875);
FORCEADD OFFPAGE..2
R 2
(-2750 2950);
FORCEPROP 2 LAST $XR0 21 
J 0
(-3004 2950);
DISPLAY 0.638298 (-3004 2950);
PAINT MONO (-3004 2950);
FORCEPROP 2 LAST $XR1 194 
J 0
(-3124 2950);
DISPLAY 0.638298 (-3124 2950);
PAINT MONO (-3124 2950);
FORCEPROP 2 LAST $XR2 201 
J 0
(-3244 2950);
DISPLAY 0.638298 (-3244 2950);
PAINT MONO (-3244 2950);
FORCEPROP 2 LAST ROOM PVCCIO_CPU0
J 0
(-3300 3025);
DISPLAY 1.361702 (-3300 3025);
PAINT ORANGE (-3300 3025);
DISPLAY INVISIBLE (-3300 3025);
FORCEPROP 2 LAST CDS_LIB mstr_standard
J 0
(-2750 2950);
PAINT ORANGE (-2750 2950);
DISPLAY INVISIBLE (-2750 2950);
FORCEPROP 2 LAST PATH I19
J 0
(-2700 3025);
DISPLAY 1.021277 (-2700 3025);
PAINT ORANGE (-2700 3025);
DISPLAY INVISIBLE (-2700 3025);
FORCEPROP 1 LAST OFFPAGE TRUE
J 2
(-3075 2825);
DISPLAY 1.170213 (-3075 2825);
PAINT GREEN (-3075 2825);
DISPLAY INVISIBLE (-3075 2825);
FORCEPROP 1 LAST COMMENT_BODY TRUE
J 2
(-2705 2855);
DISPLAY 1.170213 (-2705 2855);
PAINT GREEN (-2705 2855);
DISPLAY INVISIBLE (-2705 2855);
FORCEADD GND..1
(925 1900);
FORCEPROP 3 LASTPIN (925 1950) SIG_NAME GND\g
J 0
(935 1960);
DISPLAY 0.659574 (935 1960);
PAINT MONO (935 1960);
DISPLAY INVISIBLE (935 1960);
FORCEPROP 1 LAST VOLTAGE 0
J 0
(925 1900);
PAINT SKYBLUE (925 1900);
DISPLAY INVISIBLE (925 1900);
FORCEPROP 1 LAST SIZE 1B
J 0
(1000 1850);
DISPLAY 1.170213 (1000 1850);
PAINT AQUA (1000 1850);
DISPLAY INVISIBLE (1000 1850);
FORCEPROP 2 LAST CDS_LIB mstr_symbols
J 0
(925 1900);
PAINT ORANGE (925 1900);
DISPLAY INVISIBLE (925 1900);
FORCEPROP 2 LAST ROOM PVCCIO_CPU0
J 0
(350 1975);
DISPLAY 1.361702 (350 1975);
PAINT ORANGE (350 1975);
DISPLAY INVISIBLE (350 1975);
FORCEPROP 1 LAST PATH I2
J 0
(1000 1900);
DISPLAY 0.872340 (1000 1900);
PAINT AQUA (1000 1900);
DISPLAY INVISIBLE (1000 1900);
FORCEPROP 1 LAST BODY_TYPE PLUMBING
J 0
(880 1857);
DISPLAY 0.340426 (880 1857);
PAINT GREEN (880 1857);
DISPLAY INVISIBLE (880 1857);
FORCEPROP 1 LAST HDL_POWER GND
J 0
(925 2050);
DISPLAY 1.170213 (925 2050);
PAINT GREEN (925 2050);
DISPLAY INVISIBLE (925 2050);
FORCEADD CAP_A..1
(75 4175);
FORCEPROP 1 LAST PACK_TYPE 0402V
J 0
(125 3975);
DISPLAY 0.617021 (125 3975);
PAINT SKYBLUE (125 3975);
FORCEPROP 1 LAST PART_NUMBER D97712-004
J 0
(125 4025);
DISPLAY 0.617021 (125 4025);
PAINT BLUE (125 4025);
FORCEPROP 1 LAST MATERIAL X6S
J 0
(125 4075);
DISPLAY 0.617021 (125 4075);
PAINT SKYBLUE (125 4075);
FORCEPROP 1 LAST VOLTAGE 6.3V
J 0
(125 4175);
DISPLAY 0.617021 (125 4175);
PAINT SKYBLUE (125 4175);
FORCEPROP 1 LAST TOLERANCE 10%
J 0
(125 4125);
DISPLAY 0.617021 (125 4125);
PAINT SKYBLUE (125 4125);
FORCEPROP 1 LAST LOCATION C3P3
J 0
(125 4275);
DISPLAY 0.617021 (125 4275);
PAINT AQUA (125 4275);
FORCEPROP 1 LAST VALUE 1.0UF
J 0
(125 4225);
DISPLAY 0.617021 (125 4225);
PAINT SKYBLUE (125 4225);
FORCEPROP 1 LASTPIN (75 4075) $PN 2
J 0
(85 4055);
DISPLAY 0.787234 (85 4055);
PAINT ORANGE (85 4055);
DISPLAY INVISIBLE (85 4055);
FORCEPROP 1 LASTPIN (75 4275) $PN 1
J 0
(85 4255);
DISPLAY 0.787234 (85 4255);
PAINT ORANGE (85 4255);
DISPLAY INVISIBLE (85 4255);
FORCEPROP 2 LAST CDS_LIB dev_discrete
J 0
(75 4175);
PAINT ORANGE (75 4175);
DISPLAY INVISIBLE (75 4175);
FORCEPROP 2 LAST CDS_LOCATION C3P3
J 0
(125 4275);
DISPLAY 0.617021 (125 4275);
PAINT AQUA (125 4275);
DISPLAY INVISIBLE (125 4275);
FORCEPROP 1 LAST PATH I20
J 0
(125 4325);
DISPLAY 0.978723 (125 4325);
PAINT WHITE (125 4325);
DISPLAY INVISIBLE (125 4325);
FORCEPROP 2 LAST ROOM PVCCIO_CPU0
J 0
(125 4325);
DISPLAY 1.361702 (125 4325);
PAINT ORANGE (125 4325);
DISPLAY INVISIBLE (125 4325);
FORCEPROP 2 LAST CDS_SEC 1
J 0
(125 4375);
DISPLAY 1.021277 (125 4375);
PAINT ORANGE (125 4375);
DISPLAY INVISIBLE (125 4375);
FORCEPROP 2 LAST $SEC 1
J 0
(125 4375);
DISPLAY 0.680851 (125 4375);
PAINT MONO (125 4375);
DISPLAY INVISIBLE (125 4375);
FORCEADD GND..1
(75 3975);
FORCEPROP 3 LASTPIN (75 4025) SIG_NAME GND\g
J 0
(85 4035);
DISPLAY 0.659574 (85 4035);
PAINT MONO (85 4035);
DISPLAY INVISIBLE (85 4035);
FORCEPROP 2 LAST ROOM PVCCIO_CPU0
J 0
(-500 4050);
DISPLAY 1.361702 (-500 4050);
PAINT ORANGE (-500 4050);
DISPLAY INVISIBLE (-500 4050);
FORCEPROP 2 LAST CDS_LIB mstr_symbols
J 0
(75 3975);
PAINT ORANGE (75 3975);
DISPLAY INVISIBLE (75 3975);
FORCEPROP 1 LAST VOLTAGE 0
J 0
(75 3975);
PAINT SKYBLUE (75 3975);
DISPLAY INVISIBLE (75 3975);
FORCEPROP 1 LAST PATH I21
J 0
(150 3975);
DISPLAY 0.872340 (150 3975);
PAINT AQUA (150 3975);
DISPLAY INVISIBLE (150 3975);
FORCEPROP 1 LAST SIZE 1B
J 0
(150 3925);
DISPLAY 1.170213 (150 3925);
PAINT AQUA (150 3925);
DISPLAY INVISIBLE (150 3925);
FORCEPROP 1 LAST BODY_TYPE PLUMBING
J 0
(30 3932);
DISPLAY 0.340426 (30 3932);
PAINT GREEN (30 3932);
DISPLAY INVISIBLE (30 3932);
FORCEPROP 1 LAST HDL_POWER GND
J 0
(75 4125);
DISPLAY 1.170213 (75 4125);
PAINT GREEN (75 4125);
DISPLAY INVISIBLE (75 4125);
FORCEADD CAP_A..1
(-325 4175);
FORCEPROP 1 LASTPIN (-325 4075) $PN 2
J 0
(-315 4055);
DISPLAY 0.617021 (-315 4055);
PAINT ORANGE (-315 4055);
FORCEPROP 1 LAST PACK_TYPE 0402V
J 0
(-275 3975);
DISPLAY 0.617021 (-275 3975);
PAINT SKYBLUE (-275 3975);
FORCEPROP 1 LAST MATERIAL X7R
J 0
(-275 4075);
DISPLAY 0.617021 (-275 4075);
PAINT SKYBLUE (-275 4075);
FORCEPROP 1 LASTPIN (-325 4275) $PN 1
J 0
(-315 4255);
DISPLAY 0.617021 (-315 4255);
PAINT ORANGE (-315 4255);
FORCEPROP 1 LAST VOLTAGE 16V
J 0
(-275 4175);
DISPLAY 0.617021 (-275 4175);
PAINT SKYBLUE (-275 4175);
FORCEPROP 1 LAST TOLERANCE 10%
J 0
(-275 4125);
DISPLAY 0.617021 (-275 4125);
PAINT SKYBLUE (-275 4125);
FORCEPROP 1 LAST VALUE 0.1UF
J 0
(-275 4225);
DISPLAY 0.617021 (-275 4225);
PAINT SKYBLUE (-275 4225);
FORCEPROP 1 LAST LOCATION C3P7
J 0
(-275 4275);
DISPLAY 0.617021 (-275 4275);
PAINT AQUA (-275 4275);
FORCEPROP 1 LAST PART_NUMBER A36096-030
J 0
(-275 4025);
DISPLAY 0.617021 (-275 4025);
PAINT BLUE (-275 4025);
FORCEPROP 2 LAST CDS_LIB dev_discrete
J 0
(-325 4175);
PAINT ORANGE (-325 4175);
DISPLAY INVISIBLE (-325 4175);
FORCEPROP 2 LAST CDS_LOCATION C3P7
J 0
(-275 4275);
DISPLAY 0.617021 (-275 4275);
PAINT AQUA (-275 4275);
DISPLAY INVISIBLE (-275 4275);
FORCEPROP 1 LAST PATH I22
J 0
(-275 4325);
DISPLAY 0.978723 (-275 4325);
PAINT WHITE (-275 4325);
DISPLAY INVISIBLE (-275 4325);
FORCEPROP 2 LAST ROOM PVCCIO_CPU0
J 0
(-275 4325);
DISPLAY 1.361702 (-275 4325);
PAINT ORANGE (-275 4325);
DISPLAY INVISIBLE (-275 4325);
FORCEPROP 2 LAST CDS_SEC 1
J 0
(-275 4325);
PAINT ORANGE (-275 4325);
DISPLAY INVISIBLE (-275 4325);
FORCEPROP 2 LAST SEC 1
J 0
(-275 4325);
DISPLAY 0.680851 (-275 4325);
PAINT MONO (-275 4325);
DISPLAY INVISIBLE (-275 4325);
FORCEPROP 2 LAST SEC_TYPE 0402V
J 0
(-275 4375);
DISPLAY 1.021277 (-275 4375);
PAINT ORANGE (-275 4375);
DISPLAY INVISIBLE (-275 4375);
FORCEADD GND..1
(-325 3975);
FORCEPROP 3 LASTPIN (-325 4025) SIG_NAME GND\g
J 0
(-315 4035);
DISPLAY 0.659574 (-315 4035);
PAINT MONO (-315 4035);
DISPLAY INVISIBLE (-315 4035);
FORCEPROP 2 LAST CDS_LIB mstr_symbols
J 0
(-325 3975);
PAINT ORANGE (-325 3975);
DISPLAY INVISIBLE (-325 3975);
FORCEPROP 1 LAST VOLTAGE 0
J 0
(-325 3975);
PAINT SKYBLUE (-325 3975);
DISPLAY INVISIBLE (-325 3975);
FORCEPROP 1 LAST PATH I23
J 0
(-250 3975);
DISPLAY 0.872340 (-250 3975);
PAINT AQUA (-250 3975);
DISPLAY INVISIBLE (-250 3975);
FORCEPROP 1 LAST SIZE 1B
J 0
(-250 3925);
DISPLAY 1.170213 (-250 3925);
PAINT AQUA (-250 3925);
DISPLAY INVISIBLE (-250 3925);
FORCEPROP 2 LAST ROOM PVCCIO_CPU0
J 0
(-900 4050);
DISPLAY 1.361702 (-900 4050);
PAINT ORANGE (-900 4050);
DISPLAY INVISIBLE (-900 4050);
FORCEPROP 1 LAST BODY_TYPE PLUMBING
J 0
(-370 3932);
DISPLAY 0.340426 (-370 3932);
PAINT GREEN (-370 3932);
DISPLAY INVISIBLE (-370 3932);
FORCEPROP 1 LAST HDL_POWER GND
J 0
(-325 4125);
DISPLAY 1.170213 (-325 4125);
PAINT GREEN (-325 4125);
DISPLAY INVISIBLE (-325 4125);
FORCEADD RES..2
(-625 4525);
FORCEPROP 1 LASTPIN (-625 4425) $PN 2
J 0
(-620 4435);
DISPLAY 0.617021 (-620 4435);
PAINT ORANGE (-620 4435);
FORCEPROP 1 LAST TOLERANCE 5%
J 0
(-580 4550);
DISPLAY 0.617021 (-580 4550);
PAINT SKYBLUE (-580 4550);
FORCEPROP 1 LASTPIN (-625 4625) $PN 1
J 0
(-620 4587);
DISPLAY 0.617021 (-620 4587);
PAINT ORANGE (-620 4587);
FORCEPROP 1 LAST WATTAGE 1/16W
J 0
(-585 4500);
DISPLAY 0.617021 (-585 4500);
PAINT SKYBLUE (-585 4500);
FORCEPROP 1 LAST MATERIAL CHIP
J 0
(-585 4450);
DISPLAY 0.617021 (-585 4450);
PAINT SKYBLUE (-585 4450);
FORCEPROP 1 LAST PACK_TYPE 0402
J 0
(-585 4350);
DISPLAY 0.617021 (-585 4350);
PAINT SKYBLUE (-585 4350);
FORCEPROP 1 LAST VALUE 0.0
J 0
(-580 4600);
DISPLAY 0.617021 (-580 4600);
PAINT SKYBLUE (-580 4600);
FORCEPROP 1 LAST PART_NUMBER G21497-005
J 0
(-585 4400);
DISPLAY 0.617021 (-585 4400);
PAINT BLUE (-585 4400);
FORCEPROP 1 LAST LOCATION R3P22
J 0
(-580 4650);
DISPLAY 0.617021 (-580 4650);
PAINT AQUA (-580 4650);
FORCEPROP 2 LAST CDS_LIB mstr_discrete
J 0
(-625 4525);
PAINT ORANGE (-625 4525);
DISPLAY INVISIBLE (-625 4525);
FORCEPROP 2 LAST CDS_LOCATION R3P22
J 0
(-580 4650);
DISPLAY 0.617021 (-580 4650);
PAINT AQUA (-580 4650);
DISPLAY INVISIBLE (-580 4650);
FORCEPROP 0 LAST SEC 1
J 0
(-575 4700);
DISPLAY 0.680851 (-575 4700);
PAINT MONO (-575 4700);
DISPLAY INVISIBLE (-575 4700);
FORCEPROP 1 LAST PATH I24
J 0
(-575 4700);
DISPLAY 0.978723 (-575 4700);
PAINT WHITE (-575 4700);
DISPLAY INVISIBLE (-575 4700);
FORCEPROP 2 LAST ROOM PVCCIO_CPU0
J 0
(-575 4700);
DISPLAY 1.361702 (-575 4700);
PAINT ORANGE (-575 4700);
DISPLAY INVISIBLE (-575 4700);
FORCEPROP 2 LAST SEC_TYPE 0402
J 0
(-575 4750);
DISPLAY 1.021277 (-575 4750);
PAINT ORANGE (-575 4750);
DISPLAY INVISIBLE (-575 4750);
FORCEADD P3V3_STBY..1
(-625 4850);
FORCEPROP 3 LASTPIN (-625 4800) SIG_NAME P3V3_STBY\g
J 0
(-615 4810);
DISPLAY 0.659574 (-615 4810);
PAINT MONO (-615 4810);
DISPLAY INVISIBLE (-615 4810);
FORCEPROP 1 LAST VOLTAGE 3.3V
J 0
(-670 4807);
DISPLAY 0.340426 (-670 4807);
PAINT SKYBLUE (-670 4807);
DISPLAY INVISIBLE (-670 4807);
FORCEPROP 1 LAST PATH I25
J 0
(-580 4852);
DISPLAY 0.340426 (-580 4852);
PAINT GREEN (-580 4852);
DISPLAY INVISIBLE (-580 4852);
FORCEPROP 2 LAST CDS_LIB mstr_symbols
J 0
(-625 4850);
PAINT ORANGE (-625 4850);
DISPLAY INVISIBLE (-625 4850);
FORCEPROP 1 LAST SIZE 1B
J 0
(-580 4872);
DISPLAY 0.340426 (-580 4872);
PAINT GREEN (-580 4872);
DISPLAY INVISIBLE (-580 4872);
FORCEPROP 1 LAST BODY_TYPE PLUMBING
J 0
(-670 4807);
DISPLAY 0.340426 (-670 4807);
PAINT GREEN (-670 4807);
DISPLAY INVISIBLE (-670 4807);
FORCEPROP 1 LAST HDL_POWER P3V3_STBY
J 0
(-925 4725);
DISPLAY 0.872340 (-925 4725);
PAINT ORANGE (-925 4725);
DISPLAY INVISIBLE (-925 4725);
FORCEADD OFFPAGE..1
(-3025 3975);
FORCEPROP 2 LAST $XR0 21 
J 0
(-3276 3975);
DISPLAY 0.638298 (-3276 3975);
PAINT MONO (-3276 3975);
FORCEPROP 2 LAST $XR1 194 
J 0
(-3396 3975);
DISPLAY 0.638298 (-3396 3975);
PAINT MONO (-3396 3975);
FORCEPROP 2 LAST $XR2 201 
J 0
(-3516 3975);
DISPLAY 0.638298 (-3516 3975);
PAINT MONO (-3516 3975);
FORCEPROP 2 LAST PATH I26
J 0
(-3225 4025);
DISPLAY 1.021277 (-3225 4025);
PAINT ORANGE (-3225 4025);
DISPLAY INVISIBLE (-3225 4025);
FORCEPROP 2 LAST CDS_LIB mstr_standard
J 0
(-3025 3975);
PAINT ORANGE (-3025 3975);
DISPLAY INVISIBLE (-3025 3975);
FORCEPROP 2 LAST ROOM PVCCIO_CPU0
J 0
(-3575 4050);
DISPLAY 1.361702 (-3575 4050);
PAINT ORANGE (-3575 4050);
DISPLAY INVISIBLE (-3575 4050);
FORCEPROP 1 LAST OFFPAGE TRUE
J 0
(-2700 3850);
DISPLAY 1.170213 (-2700 3850);
PAINT GREEN (-2700 3850);
DISPLAY INVISIBLE (-2700 3850);
FORCEPROP 1 LAST COMMENT_BODY TRUE
J 0
(-2900 3875);
DISPLAY 1.170213 (-2900 3875);
PAINT GREEN (-2900 3875);
DISPLAY INVISIBLE (-2900 3875);
FORCEADD PVCCIO_CPU0..1
(-2125 4875);
FORCEPROP 3 LASTPIN (-2125 4825) SIG_NAME PVCCIO_CPU0\g
J 0
(-2115 4835);
DISPLAY 0.659574 (-2115 4835);
PAINT MONO (-2115 4835);
DISPLAY INVISIBLE (-2115 4835);
FORCEPROP 1 LAST VOLTAGE 1.1V
J 0
(-2170 4832);
DISPLAY 0.340426 (-2170 4832);
PAINT SKYBLUE (-2170 4832);
DISPLAY INVISIBLE (-2170 4832);
FORCEPROP 1 LAST PATH I27
J 0
(-2075 4900);
DISPLAY 0.872340 (-2075 4900);
PAINT AQUA (-2075 4900);
DISPLAY INVISIBLE (-2075 4900);
FORCEPROP 2 LAST CDS_LIB mstr_symbols
J 0
(-2125 4875);
PAINT ORANGE (-2125 4875);
DISPLAY INVISIBLE (-2125 4875);
FORCEPROP 1 LAST BODY_TYPE PLUMBING
J 0
(-2170 4832);
DISPLAY 0.340426 (-2170 4832);
PAINT GREEN (-2170 4832);
DISPLAY INVISIBLE (-2170 4832);
FORCEPROP 1 LAST HDL_POWER PVCCIO_CPU0
J 1
(-2125 4925);
DISPLAY 0.872340 (-2125 4925);
PAINT GREEN (-2125 4925);
DISPLAY INVISIBLE (-2125 4925);
FORCEADD RES..2
(-2125 4525);
FORCEPROP 1 LASTPIN (-2125 4425) $PN 2
J 0
(-2120 4435);
DISPLAY 0.617021 (-2120 4435);
PAINT ORANGE (-2120 4435);
FORCEPROP 1 LASTPIN (-2125 4625) $PN 1
J 0
(-2120 4587);
DISPLAY 0.617021 (-2120 4587);
PAINT ORANGE (-2120 4587);
FORCEPROP 1 LAST WATTAGE 1/16W
J 0
(-2085 4500);
DISPLAY 0.617021 (-2085 4500);
PAINT SKYBLUE (-2085 4500);
FORCEPROP 1 LAST PACK_TYPE 0402
J 0
(-2085 4350);
DISPLAY 0.617021 (-2085 4350);
PAINT SKYBLUE (-2085 4350);
FORCEPROP 1 LAST TOLERANCE 1%
J 0
(-2080 4550);
DISPLAY 0.617021 (-2080 4550);
PAINT SKYBLUE (-2080 4550);
FORCEPROP 1 LAST VALUE 49.9
J 0
(-2080 4600);
DISPLAY 0.617021 (-2080 4600);
PAINT SKYBLUE (-2080 4600);
FORCEPROP 1 LAST PART_NUMBER G21796-047
J 0
(-2085 4400);
DISPLAY 0.617021 (-2085 4400);
PAINT BLUE (-2085 4400);
FORCEPROP 1 LAST LOCATION R3P17
J 0
(-2080 4650);
DISPLAY 0.617021 (-2080 4650);
PAINT AQUA (-2080 4650);
FORCEPROP 1 LAST MATERIAL EMPTY
J 0
(-2085 4450);
DISPLAY 0.617021 (-2085 4450);
PAINT RED (-2085 4450);
FORCEPROP 2 LAST CDS_LIB mstr_discrete
J 0
(-2125 4525);
PAINT ORANGE (-2125 4525);
DISPLAY INVISIBLE (-2125 4525);
FORCEPROP 2 LAST CDS_LOCATION R3P17
J 0
(-2080 4650);
DISPLAY 0.617021 (-2080 4650);
PAINT AQUA (-2080 4650);
DISPLAY INVISIBLE (-2080 4650);
FORCEPROP 1 LAST PATH I28
J 0
(-2075 4700);
DISPLAY 0.978723 (-2075 4700);
PAINT WHITE (-2075 4700);
DISPLAY INVISIBLE (-2075 4700);
FORCEPROP 2 LAST ROOM PVCCIO_CPU0
J 0
(-2075 4700);
DISPLAY 1.361702 (-2075 4700);
PAINT ORANGE (-2075 4700);
DISPLAY INVISIBLE (-2075 4700);
FORCEPROP 2 LAST SEC_TYPE 0402
J 0
(-2075 4775);
DISPLAY 1.021277 (-2075 4775);
PAINT ORANGE (-2075 4775);
DISPLAY INVISIBLE (-2075 4775);
FORCEPROP 2 LAST SEC 1
J 0
(-2075 4775);
PAINT MONO (-2075 4775);
DISPLAY INVISIBLE (-2075 4775);
FORCEADD RES..1
(-1975 3975);
FORCEPROP 1 LASTPIN (-2075 3975) $PN 1
J 0
(-2063 3987);
DISPLAY 0.617021 (-2063 3987);
PAINT ORANGE (-2063 3987);
FORCEPROP 1 LAST WATTAGE 1/16W
J 2
(-1925 4000);
DISPLAY 0.617021 (-1925 4000);
PAINT SKYBLUE (-1925 4000);
FORCEPROP 1 LAST VALUE 150.0
J 2
(-1975 4050);
DISPLAY 0.617021 (-1975 4050);
PAINT SKYBLUE (-1975 4050);
FORCEPROP 1 LAST TOLERANCE 1%
J 0
(-1925 4050);
DISPLAY 0.617021 (-1925 4050);
PAINT SKYBLUE (-1925 4050);
FORCEPROP 1 LASTPIN (-1875 3975) $PN 2
J 0
(-1913 3987);
DISPLAY 0.617021 (-1913 3987);
PAINT ORANGE (-1913 3987);
FORCEPROP 1 LAST PACK_TYPE 0402
J 0
(-1800 4050);
DISPLAY 0.617021 (-1800 4050);
PAINT SKYBLUE (-1800 4050);
FORCEPROP 1 LAST MATERIAL CHIP
J 0
(-1875 4000);
DISPLAY 0.617021 (-1875 4000);
PAINT SKYBLUE (-1875 4000);
FORCEPROP 1 LAST PART_NUMBER G21796-009
J 0
(-2075 4100);
DISPLAY 0.617021 (-2075 4100);
PAINT BLUE (-2075 4100);
FORCEPROP 1 LAST LOCATION R3P15
J 0
(-2075 4150);
DISPLAY 0.617021 (-2075 4150);
PAINT AQUA (-2075 4150);
FORCEPROP 2 LAST CDS_LIB mstr_discrete
J 0
(-1975 3975);
PAINT ORANGE (-1975 3975);
DISPLAY INVISIBLE (-1975 3975);
FORCEPROP 2 LAST ROOM PVCCIO_CPU0
J 0
(-2075 4200);
DISPLAY 1.361702 (-2075 4200);
PAINT ORANGE (-2075 4200);
DISPLAY INVISIBLE (-2075 4200);
FORCEPROP 2 LAST CDS_LOCATION R3P15
J 0
(-2075 4150);
DISPLAY 0.617021 (-2075 4150);
PAINT AQUA (-2075 4150);
DISPLAY INVISIBLE (-2075 4150);
FORCEPROP 1 LAST PATH I29
J 0
(-2025 4125);
DISPLAY 0.978723 (-2025 4125);
PAINT WHITE (-2025 4125);
DISPLAY INVISIBLE (-2025 4125);
FORCEPROP 2 LAST SEC 1
J 0
(-2025 4200);
DISPLAY 0.680851 (-2025 4200);
PAINT MONO (-2025 4200);
DISPLAY INVISIBLE (-2025 4200);
FORCEPROP 2 LAST SEC_TYPE 0402
J 0
(-2025 4200);
DISPLAY 1.021277 (-2025 4200);
PAINT ORANGE (-2025 4200);
DISPLAY INVISIBLE (-2025 4200);
FORCEADD OFFPAGE..2
(2700 3000);
FORCEPROP 2 LAST $XR0 212 
J 0
(2889 3000);
DISPLAY 0.638298 (2889 3000);
PAINT MONO (2889 3000);
FORCEPROP 2 LAST CDS_LIB mstr_standard
J 0
(2700 3000);
PAINT ORANGE (2700 3000);
DISPLAY INVISIBLE (2700 3000);
FORCEPROP 2 LAST ROOM PVCCIO_CPU0
J 0
(2275 3075);
DISPLAY 1.361702 (2275 3075);
PAINT ORANGE (2275 3075);
DISPLAY INVISIBLE (2275 3075);
FORCEPROP 2 LAST PATH I3
J 0
(2875 3075);
DISPLAY 1.021277 (2875 3075);
PAINT ORANGE (2875 3075);
DISPLAY INVISIBLE (2875 3075);
FORCEPROP 1 LAST OFFPAGE TRUE
J 0
(3025 2875);
DISPLAY 1.170213 (3025 2875);
PAINT GREEN (3025 2875);
DISPLAY INVISIBLE (3025 2875);
FORCEPROP 1 LAST COMMENT_BODY TRUE
J 0
(2655 2905);
DISPLAY 1.170213 (2655 2905);
PAINT GREEN (2655 2905);
DISPLAY INVISIBLE (2655 2905);
FORCEADD VCC_CORE..1
(-2500 4850);
FORCEPROP 3 LASTPIN (-2500 4800) SIG_NAME VR_FET_SW_P12V_STBY_PVCCIO_CPU0\g
J 0
(-2490 4810);
DISPLAY 0.659574 (-2490 4810);
PAINT MONO (-2490 4810);
DISPLAY INVISIBLE (-2490 4810);
FORCEPROP 1 LAST HDL_POWER VR_FET_SW_P12V_STBY_PVCCIO_CPU0
J 1
(-2775 4900);
DISPLAY 0.617021 (-2775 4900);
PAINT GREEN (-2775 4900);
FORCEPROP 2 LAST CDS_LIB mstr_symbols
J 0
(-2500 4850);
PAINT ORANGE (-2500 4850);
DISPLAY INVISIBLE (-2500 4850);
FORCEPROP 1 LAST PATH I30
J 0
(-2450 4875);
DISPLAY 0.872340 (-2450 4875);
PAINT AQUA (-2450 4875);
DISPLAY INVISIBLE (-2450 4875);
FORCEADD RES..2
(-2500 4650);
FORCEPROP 1 LAST LOCATION R3P12
J 0
(-2680 4650);
DISPLAY 0.617021 (-2680 4650);
PAINT AQUA (-2680 4650);
FORCEPROP 1 LASTPIN (-2500 4550) $PN 2
J 0
(-2495 4560);
DISPLAY 0.617021 (-2495 4560);
PAINT ORANGE (-2495 4560);
FORCEPROP 1 LAST PACK_TYPE 0402
J 0
(-2460 4475);
DISPLAY 0.617021 (-2460 4475);
PAINT SKYBLUE (-2460 4475);
FORCEPROP 1 LAST MATERIAL CHIP
J 0
(-2460 4575);
DISPLAY 0.617021 (-2460 4575);
PAINT SKYBLUE (-2460 4575);
FORCEPROP 1 LAST PART_NUMBER G21796-160
J 0
(-2485 4525);
DISPLAY 0.617021 (-2485 4525);
PAINT BLUE (-2485 4525);
FORCEPROP 1 LASTPIN (-2500 4750) $PN 1
J 0
(-2495 4712);
DISPLAY 0.617021 (-2495 4712);
PAINT ORANGE (-2495 4712);
FORCEPROP 1 LAST TOLERANCE 1%
J 0
(-2455 4675);
DISPLAY 0.617021 (-2455 4675);
PAINT SKYBLUE (-2455 4675);
FORCEPROP 1 LAST WATTAGE 1/16W
J 0
(-2460 4625);
DISPLAY 0.617021 (-2460 4625);
PAINT SKYBLUE (-2460 4625);
FORCEPROP 1 LAST VALUE 100.0K
J 0
(-2455 4725);
DISPLAY 0.617021 (-2455 4725);
PAINT SKYBLUE (-2455 4725);
FORCEPROP 2 LAST CDS_LOCATION R3P12
J 0
(-2680 4650);
DISPLAY 0.617021 (-2680 4650);
PAINT AQUA (-2680 4650);
DISPLAY INVISIBLE (-2680 4650);
FORCEPROP 2 LAST CDS_LIB mstr_discrete
J 0
(-2500 4650);
PAINT ORANGE (-2500 4650);
DISPLAY INVISIBLE (-2500 4650);
FORCEPROP 2 LAST ROOM PVCCIO_CPU0
J 0
(-2450 4825);
DISPLAY 1.361702 (-2450 4825);
PAINT ORANGE (-2450 4825);
DISPLAY INVISIBLE (-2450 4825);
FORCEPROP 1 LAST PATH I31
J 0
(-2450 4825);
DISPLAY 0.978723 (-2450 4825);
PAINT WHITE (-2450 4825);
DISPLAY INVISIBLE (-2450 4825);
FORCEPROP 2 LAST NO_XNET_CONNECTION 1
J 0
(-2450 4875);
PAINT MONO (-2450 4875);
DISPLAY INVISIBLE (-2450 4875);
FORCEPROP 2 LAST SEC 1
J 0
(-2450 4875);
DISPLAY 0.680851 (-2450 4875);
PAINT MONO (-2450 4875);
DISPLAY INVISIBLE (-2450 4875);
FORCEPROP 2 LAST SEC_TYPE 0402
J 0
(-2450 4875);
DISPLAY 1.021277 (-2450 4875);
PAINT ORANGE (-2450 4875);
DISPLAY INVISIBLE (-2450 4875);
FORCEADD RES..2
(-2500 4300);
FORCEPROP 1 LAST LOCATION R3P16
J 0
(-2655 4275);
DISPLAY 0.617021 (-2655 4275);
PAINT AQUA (-2655 4275);
FORCEPROP 1 LASTPIN (-2500 4200) $PN 2
J 0
(-2495 4210);
DISPLAY 0.617021 (-2495 4210);
PAINT ORANGE (-2495 4210);
FORCEPROP 1 LAST WATTAGE 1/16W
J 0
(-2460 4275);
DISPLAY 0.617021 (-2460 4275);
PAINT SKYBLUE (-2460 4275);
FORCEPROP 1 LAST MATERIAL CHIP
J 0
(-2460 4225);
DISPLAY 0.617021 (-2460 4225);
PAINT SKYBLUE (-2460 4225);
FORCEPROP 1 LAST PACK_TYPE 0402
J 0
(-2460 4125);
DISPLAY 0.617021 (-2460 4125);
PAINT SKYBLUE (-2460 4125);
FORCEPROP 1 LAST TOLERANCE 1%
J 0
(-2455 4325);
DISPLAY 0.617021 (-2455 4325);
PAINT SKYBLUE (-2455 4325);
FORCEPROP 1 LASTPIN (-2500 4400) $PN 1
J 0
(-2495 4362);
DISPLAY 0.617021 (-2495 4362);
PAINT ORANGE (-2495 4362);
FORCEPROP 1 LAST VALUE 1.5K
J 0
(-2455 4375);
DISPLAY 0.617021 (-2455 4375);
PAINT SKYBLUE (-2455 4375);
FORCEPROP 1 LAST PART_NUMBER G21796-003
J 0
(-2460 4175);
DISPLAY 0.617021 (-2460 4175);
PAINT BLUE (-2460 4175);
FORCEPROP 2 LAST CDS_LOCATION R3P16
J 0
(-2655 4275);
DISPLAY 0.617021 (-2655 4275);
PAINT AQUA (-2655 4275);
DISPLAY INVISIBLE (-2655 4275);
FORCEPROP 2 LAST CDS_LIB mstr_discrete
J 0
(-2500 4300);
PAINT ORANGE (-2500 4300);
DISPLAY INVISIBLE (-2500 4300);
FORCEPROP 2 LAST ROOM PVCCIO_CPU0
J 0
(-2450 4475);
DISPLAY 1.361702 (-2450 4475);
PAINT ORANGE (-2450 4475);
DISPLAY INVISIBLE (-2450 4475);
FORCEPROP 1 LAST PATH I32
J 0
(-2450 4475);
DISPLAY 0.978723 (-2450 4475);
PAINT WHITE (-2450 4475);
DISPLAY INVISIBLE (-2450 4475);
FORCEPROP 2 LAST SEC 1
J 0
(-2450 4525);
DISPLAY 0.680851 (-2450 4525);
PAINT MONO (-2450 4525);
DISPLAY INVISIBLE (-2450 4525);
FORCEPROP 2 LAST SEC_TYPE 0402
J 0
(-2450 4525);
DISPLAY 1.021277 (-2450 4525);
PAINT ORANGE (-2450 4525);
DISPLAY INVISIBLE (-2450 4525);
FORCEADD CAP..1
R 2
(-2725 4275);
FORCEPROP 1 LAST PACK_TYPE 0402LF
J 2
(-2775 4075);
DISPLAY 0.617021 (-2775 4075);
PAINT SKYBLUE (-2775 4075);
FORCEPROP 1 LAST MATERIAL X7R
J 2
(-2775 4175);
DISPLAY 0.617021 (-2775 4175);
PAINT SKYBLUE (-2775 4175);
FORCEPROP 1 LAST VOLTAGE 50V
J 2
(-2775 4275);
DISPLAY 0.617021 (-2775 4275);
PAINT SKYBLUE (-2775 4275);
FORCEPROP 1 LAST TOLERANCE 10%
J 2
(-2775 4225);
DISPLAY 0.617021 (-2775 4225);
PAINT SKYBLUE (-2775 4225);
FORCEPROP 1 LAST VALUE 1000PF
J 2
(-2775 4325);
DISPLAY 0.617021 (-2775 4325);
PAINT SKYBLUE (-2775 4325);
FORCEPROP 1 LAST PART_NUMBER A36096-046
J 2
(-2775 4125);
DISPLAY 0.617021 (-2775 4125);
PAINT BLUE (-2775 4125);
FORCEPROP 1 LAST LOCATION C3P2
J 2
(-2775 4375);
DISPLAY 0.617021 (-2775 4375);
PAINT AQUA (-2775 4375);
FORCEPROP 1 LASTPIN (-2725 4175) $PN 2
J 2
(-2735 4155);
DISPLAY 0.617021 (-2735 4155);
PAINT ORANGE (-2735 4155);
FORCEPROP 1 LASTPIN (-2725 4375) $PN 1
J 2
(-2735 4355);
DISPLAY 0.617021 (-2735 4355);
PAINT ORANGE (-2735 4355);
FORCEPROP 2 LAST CDS_LIB mstr_discrete
J 2
(-2725 4275);
PAINT ORANGE (-2725 4275);
DISPLAY INVISIBLE (-2725 4275);
FORCEPROP 2 LAST SEC 1
J 0
(-2775 4500);
DISPLAY 0.680851 (-2775 4500);
PAINT MONO (-2775 4500);
DISPLAY INVISIBLE (-2775 4500);
FORCEPROP 2 LAST SEC_TYPE 0402LF
J 0
(-2775 4500);
DISPLAY 1.021277 (-2775 4500);
PAINT ORANGE (-2775 4500);
DISPLAY INVISIBLE (-2775 4500);
FORCEPROP 2 LAST ROOM PVCCIO_CPU0
J 0
(-2775 4425);
DISPLAY 1.361702 (-2775 4425);
PAINT ORANGE (-2775 4425);
DISPLAY INVISIBLE (-2775 4425);
FORCEPROP 1 LAST PATH I33
J 2
(-2775 4425);
DISPLAY 0.978723 (-2775 4425);
PAINT WHITE (-2775 4425);
DISPLAY INVISIBLE (-2775 4425);
FORCEPROP 2 LAST CDS_LOCATION C3P2
J 2
(-2775 4375);
DISPLAY 0.617021 (-2775 4375);
PAINT AQUA (-2775 4375);
DISPLAY INVISIBLE (-2775 4375);
FORCEADD GND..1
(-2500 4100);
FORCEPROP 3 LASTPIN (-2500 4150) SIG_NAME GND\g
J 0
(-2490 4160);
DISPLAY 0.659574 (-2490 4160);
PAINT MONO (-2490 4160);
DISPLAY INVISIBLE (-2490 4160);
FORCEPROP 1 LAST SIZE 1B
J 0
(-2425 4050);
DISPLAY 1.170213 (-2425 4050);
PAINT AQUA (-2425 4050);
DISPLAY INVISIBLE (-2425 4050);
FORCEPROP 2 LAST ROOM PVCCIO_CPU0
J 0
(-3075 4175);
DISPLAY 1.361702 (-3075 4175);
PAINT ORANGE (-3075 4175);
DISPLAY INVISIBLE (-3075 4175);
FORCEPROP 2 LAST CDS_LIB mstr_symbols
J 0
(-2500 4100);
PAINT ORANGE (-2500 4100);
DISPLAY INVISIBLE (-2500 4100);
FORCEPROP 1 LAST VOLTAGE 0
J 0
(-2500 4100);
PAINT SKYBLUE (-2500 4100);
DISPLAY INVISIBLE (-2500 4100);
FORCEPROP 1 LAST PATH I34
J 0
(-2425 4100);
DISPLAY 0.872340 (-2425 4100);
PAINT AQUA (-2425 4100);
DISPLAY INVISIBLE (-2425 4100);
FORCEPROP 1 LAST BODY_TYPE PLUMBING
J 0
(-2545 4057);
DISPLAY 0.340426 (-2545 4057);
PAINT GREEN (-2545 4057);
DISPLAY INVISIBLE (-2545 4057);
FORCEPROP 1 LAST HDL_POWER GND
J 0
(-2500 4250);
DISPLAY 1.170213 (-2500 4250);
PAINT GREEN (-2500 4250);
DISPLAY INVISIBLE (-2500 4250);
FORCEADD GND..1
(-2725 4075);
FORCEPROP 3 LASTPIN (-2725 4125) SIG_NAME GND\g
J 0
(-2715 4135);
DISPLAY 0.659574 (-2715 4135);
PAINT MONO (-2715 4135);
DISPLAY INVISIBLE (-2715 4135);
FORCEPROP 1 LAST SIZE 1B
J 0
(-2650 4025);
DISPLAY 1.170213 (-2650 4025);
PAINT AQUA (-2650 4025);
DISPLAY INVISIBLE (-2650 4025);
FORCEPROP 1 LAST PATH I35
J 0
(-2650 4075);
DISPLAY 0.872340 (-2650 4075);
PAINT AQUA (-2650 4075);
DISPLAY INVISIBLE (-2650 4075);
FORCEPROP 2 LAST CDS_LIB mstr_symbols
J 0
(-2725 4075);
PAINT ORANGE (-2725 4075);
DISPLAY INVISIBLE (-2725 4075);
FORCEPROP 1 LAST VOLTAGE 0
J 0
(-2725 4075);
PAINT SKYBLUE (-2725 4075);
DISPLAY INVISIBLE (-2725 4075);
FORCEPROP 2 LAST ROOM PVCCIO_CPU0
J 0
(-3300 4150);
DISPLAY 1.361702 (-3300 4150);
PAINT ORANGE (-3300 4150);
DISPLAY INVISIBLE (-3300 4150);
FORCEPROP 1 LAST BODY_TYPE PLUMBING
J 0
(-2770 4032);
DISPLAY 0.340426 (-2770 4032);
PAINT GREEN (-2770 4032);
DISPLAY INVISIBLE (-2770 4032);
FORCEPROP 1 LAST HDL_POWER GND
J 0
(-2725 4225);
DISPLAY 1.170213 (-2725 4225);
PAINT GREEN (-2725 4225);
DISPLAY INVISIBLE (-2725 4225);
FORCEADD OFFPAGE..2
R 2
(-3325 4500);
FORCEPROP 2 LAST $XR0 211 
J 0
(-3610 4500);
DISPLAY 0.638298 (-3610 4500);
PAINT MONO (-3610 4500);
FORCEPROP 2 LAST ROOM PVCCIO_CPU0
J 0
(-3875 4575);
DISPLAY 1.361702 (-3875 4575);
PAINT ORANGE (-3875 4575);
DISPLAY INVISIBLE (-3875 4575);
FORCEPROP 2 LAST PATH I36
J 0
(-3575 4550);
DISPLAY 1.021277 (-3575 4550);
PAINT ORANGE (-3575 4550);
DISPLAY INVISIBLE (-3575 4550);
FORCEPROP 2 LAST CDS_LIB mstr_standard
J 2
(-3325 4500);
PAINT ORANGE (-3325 4500);
DISPLAY INVISIBLE (-3325 4500);
FORCEPROP 1 LAST OFFPAGE TRUE
J 2
(-3650 4375);
DISPLAY 1.170213 (-3650 4375);
PAINT GREEN (-3650 4375);
DISPLAY INVISIBLE (-3650 4375);
FORCEPROP 1 LAST COMMENT_BODY TRUE
J 2
(-3280 4405);
DISPLAY 1.170213 (-3280 4405);
PAINT GREEN (-3280 4405);
DISPLAY INVISIBLE (-3280 4405);
FORCEADD OFFPAGE..1
(-2750 3150);
FORCEPROP 2 LAST $XR0 211 
J 0
(-3002 3150);
DISPLAY 0.638298 (-3002 3150);
PAINT MONO (-3002 3150);
FORCEPROP 2 LAST ROOM PVCCIO_CPU0
J 0
(-3300 3225);
DISPLAY 1.361702 (-3300 3225);
PAINT ORANGE (-3300 3225);
DISPLAY INVISIBLE (-3300 3225);
FORCEPROP 2 LAST CDS_LIB mstr_standard
J 0
(-2750 3150);
PAINT ORANGE (-2750 3150);
DISPLAY INVISIBLE (-2750 3150);
FORCEPROP 2 LAST PATH I37
J 0
(-2700 3225);
DISPLAY 1.021277 (-2700 3225);
PAINT ORANGE (-2700 3225);
DISPLAY INVISIBLE (-2700 3225);
FORCEPROP 1 LAST OFFPAGE TRUE
J 0
(-2425 3025);
DISPLAY 1.170213 (-2425 3025);
PAINT GREEN (-2425 3025);
DISPLAY INVISIBLE (-2425 3025);
FORCEPROP 1 LAST COMMENT_BODY TRUE
J 0
(-2625 3050);
DISPLAY 1.170213 (-2625 3050);
PAINT GREEN (-2625 3050);
DISPLAY INVISIBLE (-2625 3050);
FORCEADD OFFPAGE..1
(-2750 3450);
FORCEPROP 2 LAST $XR0 212 
J 0
(-3002 3450);
DISPLAY 0.638298 (-3002 3450);
PAINT MONO (-3002 3450);
FORCEPROP 2 LAST ROOM PVCCIO_CPU0
J 0
(-3300 3525);
DISPLAY 1.361702 (-3300 3525);
PAINT ORANGE (-3300 3525);
DISPLAY INVISIBLE (-3300 3525);
FORCEPROP 2 LAST CDS_LIB mstr_standard
J 0
(-2750 3450);
PAINT ORANGE (-2750 3450);
DISPLAY INVISIBLE (-2750 3450);
FORCEPROP 2 LAST PATH I39
J 0
(-2700 3525);
DISPLAY 1.021277 (-2700 3525);
PAINT ORANGE (-2700 3525);
DISPLAY INVISIBLE (-2700 3525);
FORCEPROP 1 LAST OFFPAGE TRUE
J 0
(-2425 3325);
DISPLAY 1.170213 (-2425 3325);
PAINT GREEN (-2425 3325);
DISPLAY INVISIBLE (-2425 3325);
FORCEPROP 1 LAST COMMENT_BODY TRUE
J 0
(-2625 3350);
DISPLAY 1.170213 (-2625 3350);
PAINT GREEN (-2625 3350);
DISPLAY INVISIBLE (-2625 3350);
FORCEADD OFFPAGE..1
(-2750 3400);
FORCEPROP 2 LAST $XR0 212 
J 0
(-3002 3400);
DISPLAY 0.638298 (-3002 3400);
PAINT MONO (-3002 3400);
FORCEPROP 2 LAST ROOM PVCCIO_CPU0
J 0
(-3300 3475);
DISPLAY 1.361702 (-3300 3475);
PAINT ORANGE (-3300 3475);
DISPLAY INVISIBLE (-3300 3475);
FORCEPROP 2 LAST CDS_LIB mstr_standard
J 0
(-2750 3400);
PAINT ORANGE (-2750 3400);
DISPLAY INVISIBLE (-2750 3400);
FORCEPROP 2 LAST PATH I40
J 0
(-2700 3475);
DISPLAY 1.021277 (-2700 3475);
PAINT ORANGE (-2700 3475);
DISPLAY INVISIBLE (-2700 3475);
FORCEPROP 1 LAST OFFPAGE TRUE
J 0
(-2425 3275);
DISPLAY 1.170213 (-2425 3275);
PAINT GREEN (-2425 3275);
DISPLAY INVISIBLE (-2425 3275);
FORCEPROP 1 LAST COMMENT_BODY TRUE
J 0
(-2625 3300);
DISPLAY 1.170213 (-2625 3300);
PAINT GREEN (-2625 3300);
DISPLAY INVISIBLE (-2625 3300);
FORCEADD OFFPAGE..1
(-2750 3300);
FORCEPROP 2 LAST $XR0 212 
J 0
(-3002 3300);
DISPLAY 0.638298 (-3002 3300);
PAINT MONO (-3002 3300);
FORCEPROP 2 LAST ROOM PVCCIO_CPU0
J 0
(-3300 3375);
DISPLAY 1.361702 (-3300 3375);
PAINT ORANGE (-3300 3375);
DISPLAY INVISIBLE (-3300 3375);
FORCEPROP 2 LAST CDS_LIB mstr_standard
J 0
(-2750 3300);
PAINT ORANGE (-2750 3300);
DISPLAY INVISIBLE (-2750 3300);
FORCEPROP 2 LAST PATH I42
J 0
(-2700 3375);
DISPLAY 1.021277 (-2700 3375);
PAINT ORANGE (-2700 3375);
DISPLAY INVISIBLE (-2700 3375);
FORCEPROP 1 LAST OFFPAGE TRUE
J 0
(-2425 3175);
DISPLAY 1.170213 (-2425 3175);
PAINT GREEN (-2425 3175);
DISPLAY INVISIBLE (-2425 3175);
FORCEPROP 1 LAST COMMENT_BODY TRUE
J 0
(-2625 3200);
DISPLAY 1.170213 (-2625 3200);
PAINT GREEN (-2625 3200);
DISPLAY INVISIBLE (-2625 3200);
FORCEADD OFFPAGE..1
(-2750 3250);
FORCEPROP 2 LAST $XR0 190 
J 0
(-3002 3250);
DISPLAY 0.638298 (-3002 3250);
PAINT MONO (-3002 3250);
FORCEPROP 2 LAST ROOM PVCCIO_CPU0
J 0
(-3300 3325);
DISPLAY 1.361702 (-3300 3325);
PAINT ORANGE (-3300 3325);
DISPLAY INVISIBLE (-3300 3325);
FORCEPROP 2 LAST CDS_LIB mstr_standard
J 0
(-2750 3250);
PAINT ORANGE (-2750 3250);
DISPLAY INVISIBLE (-2750 3250);
FORCEPROP 2 LAST PATH I43
J 0
(-2700 3325);
DISPLAY 1.021277 (-2700 3325);
PAINT ORANGE (-2700 3325);
DISPLAY INVISIBLE (-2700 3325);
FORCEPROP 1 LAST OFFPAGE TRUE
J 0
(-2425 3125);
DISPLAY 1.170213 (-2425 3125);
PAINT GREEN (-2425 3125);
DISPLAY INVISIBLE (-2425 3125);
FORCEPROP 1 LAST COMMENT_BODY TRUE
J 0
(-2625 3150);
DISPLAY 1.170213 (-2625 3150);
PAINT GREEN (-2625 3150);
DISPLAY INVISIBLE (-2625 3150);
FORCEADD RES..1
(-1575 2400);
FORCEPROP 1 LAST WATTAGE 1/16W
J 2
(-1600 2250);
DISPLAY 0.617021 (-1600 2250);
PAINT SKYBLUE (-1600 2250);
FORCEPROP 1 LAST VALUE 20.0
J 2
(-1600 2300);
DISPLAY 0.617021 (-1600 2300);
PAINT SKYBLUE (-1600 2300);
FORCEPROP 1 LAST MATERIAL CHIP
J 0
(-1575 2250);
DISPLAY 0.617021 (-1575 2250);
PAINT SKYBLUE (-1575 2250);
FORCEPROP 1 LAST PACK_TYPE 0402
J 0
(-1575 2200);
DISPLAY 0.617021 (-1575 2200);
PAINT SKYBLUE (-1575 2200);
FORCEPROP 1 LAST TOLERANCE 1%
J 0
(-1575 2300);
DISPLAY 0.617021 (-1575 2300);
PAINT SKYBLUE (-1575 2300);
FORCEPROP 1 LAST PART_NUMBER G21796-173
J 0
(-1625 2500);
DISPLAY 0.617021 (-1625 2500);
PAINT BLUE (-1625 2500);
FORCEPROP 1 LAST LOCATION R3P24
J 0
(-1625 2450);
DISPLAY 0.617021 (-1625 2450);
PAINT AQUA (-1625 2450);
FORCEPROP 1 LASTPIN (-1675 2400) $PN 1
J 0
(-1663 2412);
DISPLAY 0.787234 (-1663 2412);
PAINT ORANGE (-1663 2412);
DISPLAY INVISIBLE (-1663 2412);
FORCEPROP 2 LAST ROOM PVCCIO_CPU0
J 0
(-1625 2500);
DISPLAY 1.361702 (-1625 2500);
PAINT ORANGE (-1625 2500);
DISPLAY INVISIBLE (-1625 2500);
FORCEPROP 2 LAST CDS_LIB mstr_discrete
J 0
(-1575 2400);
PAINT ORANGE (-1575 2400);
DISPLAY INVISIBLE (-1575 2400);
FORCEPROP 2 LAST CDS_LOCATION R3P24
J 0
(-1625 2450);
DISPLAY 0.617021 (-1625 2450);
PAINT AQUA (-1625 2450);
DISPLAY INVISIBLE (-1625 2450);
FORCEPROP 1 LAST PATH I46
J 0
(-1625 2550);
DISPLAY 0.978723 (-1625 2550);
PAINT WHITE (-1625 2550);
DISPLAY INVISIBLE (-1625 2550);
FORCEPROP 2 LAST $SEC 1
J 0
(-1625 2600);
PAINT MONO (-1625 2600);
DISPLAY INVISIBLE (-1625 2600);
FORCEPROP 2 LAST CDS_SEC 1
J 0
(-1625 2600);
PAINT MONO (-1625 2600);
DISPLAY INVISIBLE (-1625 2600);
FORCEPROP 1 LASTPIN (-1475 2400) $PN 2
J 0
(-1513 2412);
DISPLAY 0.787234 (-1513 2412);
PAINT ORANGE (-1513 2412);
DISPLAY INVISIBLE (-1513 2412);
FORCEADD RES..1
(-1250 2450);
FORCEPROP 1 LAST WATTAGE 1/16W
J 2
(-1275 2300);
DISPLAY 0.617021 (-1275 2300);
PAINT SKYBLUE (-1275 2300);
FORCEPROP 1 LAST VALUE 20.0
J 2
(-1275 2350);
DISPLAY 0.617021 (-1275 2350);
PAINT SKYBLUE (-1275 2350);
FORCEPROP 1 LAST LOCATION R3P23
J 0
(-1300 2500);
DISPLAY 0.617021 (-1300 2500);
PAINT AQUA (-1300 2500);
FORCEPROP 1 LAST PACK_TYPE 0402
J 0
(-1225 2250);
DISPLAY 0.617021 (-1225 2250);
PAINT SKYBLUE (-1225 2250);
FORCEPROP 1 LAST MATERIAL CHIP
J 0
(-1250 2300);
DISPLAY 0.617021 (-1250 2300);
PAINT SKYBLUE (-1250 2300);
FORCEPROP 1 LAST TOLERANCE 1%
J 0
(-1250 2350);
DISPLAY 0.617021 (-1250 2350);
PAINT SKYBLUE (-1250 2350);
FORCEPROP 1 LAST PART_NUMBER G21796-173
J 0
(-1300 2550);
DISPLAY 0.617021 (-1300 2550);
PAINT BLUE (-1300 2550);
FORCEPROP 1 LASTPIN (-1350 2450) $PN 1
J 0
(-1338 2462);
DISPLAY 0.787234 (-1338 2462);
PAINT ORANGE (-1338 2462);
DISPLAY INVISIBLE (-1338 2462);
FORCEPROP 2 LAST CDS_LOCATION R3P23
J 0
(-1300 2500);
DISPLAY 0.617021 (-1300 2500);
PAINT AQUA (-1300 2500);
DISPLAY INVISIBLE (-1300 2500);
FORCEPROP 1 LASTPIN (-1150 2450) $PN 2
J 0
(-1188 2462);
DISPLAY 0.787234 (-1188 2462);
PAINT ORANGE (-1188 2462);
DISPLAY INVISIBLE (-1188 2462);
FORCEPROP 2 LAST CDS_LIB mstr_discrete
J 0
(-1250 2450);
PAINT ORANGE (-1250 2450);
DISPLAY INVISIBLE (-1250 2450);
FORCEPROP 2 LAST ROOM PVCCIO_CPU0
J 0
(-1300 2550);
DISPLAY 1.361702 (-1300 2550);
PAINT ORANGE (-1300 2550);
DISPLAY INVISIBLE (-1300 2550);
FORCEPROP 1 LAST PATH I47
J 0
(-1300 2600);
DISPLAY 0.978723 (-1300 2600);
PAINT WHITE (-1300 2600);
DISPLAY INVISIBLE (-1300 2600);
FORCEPROP 2 LAST $SEC 1
J 0
(-1300 2650);
PAINT MONO (-1300 2650);
DISPLAY INVISIBLE (-1300 2650);
FORCEPROP 2 LAST CDS_SEC 1
J 0
(-1300 2650);
PAINT MONO (-1300 2650);
DISPLAY INVISIBLE (-1300 2650);
FORCEADD OFFPAGE..2
R 2
(-2750 2400);
FORCEPROP 2 LAST $XR0 138 
J 0
(-3035 2400);
DISPLAY 0.638298 (-3035 2400);
PAINT MONO (-3035 2400);
FORCEPROP 2 LAST $XR1 159 
J 0
(-3155 2400);
DISPLAY 0.638298 (-3155 2400);
PAINT MONO (-3155 2400);
FORCEPROP 2 LAST $XR2 213 
J 0
(-3275 2400);
DISPLAY 0.638298 (-3275 2400);
PAINT MONO (-3275 2400);
FORCEPROP 2 LAST $XR3 235 
J 0
(-3395 2400);
DISPLAY 0.638298 (-3395 2400);
PAINT MONO (-3395 2400);
FORCEPROP 2 LAST $XR4 193 
J 0
(-3515 2400);
DISPLAY 0.638298 (-3515 2400);
PAINT MONO (-3515 2400);
FORCEPROP 2 LAST $XR5 194 
J 0
(-3635 2400);
DISPLAY 0.638298 (-3635 2400);
PAINT MONO (-3635 2400);
FORCEPROP 2 LAST $XR6 201 
J 0
(-3035 2364);
DISPLAY 0.638298 (-3035 2364);
PAINT MONO (-3035 2364);
FORCEPROP 2 LAST $XR7 206 
J 0
(-3155 2364);
DISPLAY 0.638298 (-3155 2364);
PAINT MONO (-3155 2364);
FORCEPROP 2 LAST $XR8 215 
J 0
(-3275 2364);
DISPLAY 0.638298 (-3275 2364);
PAINT MONO (-3275 2364);
FORCEPROP 2 LAST $XR9 218 
J 0
(-3395 2364);
DISPLAY 0.638298 (-3395 2364);
PAINT MONO (-3395 2364);
FORCEPROP 2 LAST $XR10 223 
J 0
(-3515 2364);
DISPLAY 0.638298 (-3515 2364);
PAINT MONO (-3515 2364);
FORCEPROP 2 LAST $XR11 226 
J 0
(-3635 2364);
DISPLAY 0.638298 (-3635 2364);
PAINT MONO (-3635 2364);
FORCEPROP 2 LAST ROOM PVCCIO_CPU0
J 0
(-3300 2475);
DISPLAY 1.361702 (-3300 2475);
PAINT ORANGE (-3300 2475);
DISPLAY INVISIBLE (-3300 2475);
FORCEPROP 2 LAST CDS_LIB mstr_standard
J 0
(-2750 2400);
PAINT ORANGE (-2750 2400);
DISPLAY INVISIBLE (-2750 2400);
FORCEPROP 2 LAST PATH I48
J 0
(-2700 2475);
DISPLAY 1.021277 (-2700 2475);
PAINT ORANGE (-2700 2475);
DISPLAY INVISIBLE (-2700 2475);
FORCEPROP 1 LAST OFFPAGE TRUE
J 2
(-3075 2275);
DISPLAY 1.170213 (-3075 2275);
PAINT GREEN (-3075 2275);
DISPLAY INVISIBLE (-3075 2275);
FORCEPROP 1 LAST COMMENT_BODY TRUE
J 2
(-2705 2305);
DISPLAY 1.170213 (-2705 2305);
PAINT GREEN (-2705 2305);
DISPLAY INVISIBLE (-2705 2305);
FORCEADD OFFPAGE..3
R 2
(-2750 2450);
FORCEPROP 2 LAST $XR0 138 
J 0
(-3030 2450);
DISPLAY 0.638298 (-3030 2450);
PAINT MONO (-3030 2450);
FORCEPROP 2 LAST $XR1 159 
J 0
(-3150 2450);
DISPLAY 0.638298 (-3150 2450);
PAINT MONO (-3150 2450);
FORCEPROP 2 LAST $XR2 193 
J 0
(-3270 2450);
DISPLAY 0.638298 (-3270 2450);
PAINT MONO (-3270 2450);
FORCEPROP 2 LAST $XR3 194 
J 0
(-3390 2450);
DISPLAY 0.638298 (-3390 2450);
PAINT MONO (-3390 2450);
FORCEPROP 2 LAST $XR4 201 
J 0
(-3510 2450);
DISPLAY 0.638298 (-3510 2450);
PAINT MONO (-3510 2450);
FORCEPROP 2 LAST $XR5 206 
J 0
(-3630 2450);
DISPLAY 0.638298 (-3630 2450);
PAINT MONO (-3630 2450);
FORCEPROP 2 LAST $XR6 213 
J 0
(-3030 2486);
DISPLAY 0.638298 (-3030 2486);
PAINT MONO (-3030 2486);
FORCEPROP 2 LAST $XR7 215 
J 0
(-3150 2486);
DISPLAY 0.638298 (-3150 2486);
PAINT MONO (-3150 2486);
FORCEPROP 2 LAST $XR8 218 
J 0
(-3270 2486);
DISPLAY 0.638298 (-3270 2486);
PAINT MONO (-3270 2486);
FORCEPROP 2 LAST $XR9 223 
J 0
(-3390 2486);
DISPLAY 0.638298 (-3390 2486);
PAINT MONO (-3390 2486);
FORCEPROP 2 LAST $XR10 226 
J 0
(-3510 2486);
DISPLAY 0.638298 (-3510 2486);
PAINT MONO (-3510 2486);
FORCEPROP 2 LAST $XR11 235 
J 0
(-3630 2486);
DISPLAY 0.638298 (-3630 2486);
PAINT MONO (-3630 2486);
FORCEPROP 2 LAST ROOM PVCCIO_CPU0
J 0
(-3300 2525);
DISPLAY 1.361702 (-3300 2525);
PAINT ORANGE (-3300 2525);
DISPLAY INVISIBLE (-3300 2525);
FORCEPROP 2 LAST CDS_LIB mstr_standard
J 0
(-2750 2450);
PAINT ORANGE (-2750 2450);
DISPLAY INVISIBLE (-2750 2450);
FORCEPROP 2 LAST PATH I49
J 0
(-2700 2525);
DISPLAY 1.021277 (-2700 2525);
PAINT ORANGE (-2700 2525);
DISPLAY INVISIBLE (-2700 2525);
FORCEPROP 1 LAST OFFPAGE TRUE
J 2
(-3075 2325);
DISPLAY 0.872340 (-3075 2325);
PAINT GREEN (-3075 2325);
DISPLAY INVISIBLE (-3075 2325);
FORCEPROP 1 LAST COMMENT_BODY TRUE
J 2
(-2700 2350);
DISPLAY 0.872340 (-2700 2350);
PAINT GREEN (-2700 2350);
DISPLAY INVISIBLE (-2700 2350);
FORCEADD GND..1
(-1025 2050);
FORCEPROP 3 LASTPIN (-1025 2100) SIG_NAME GND\g
J 0
(-1015 2110);
DISPLAY 0.659574 (-1015 2110);
PAINT MONO (-1015 2110);
DISPLAY INVISIBLE (-1015 2110);
FORCEPROP 1 LAST SIZE 1B
J 0
(-950 2000);
DISPLAY 1.170213 (-950 2000);
PAINT AQUA (-950 2000);
DISPLAY INVISIBLE (-950 2000);
FORCEPROP 2 LAST ROOM PVCCIO_CPU0
J 0
(-1600 2125);
DISPLAY 1.361702 (-1600 2125);
PAINT ORANGE (-1600 2125);
DISPLAY INVISIBLE (-1600 2125);
FORCEPROP 1 LAST VOLTAGE 0
J 0
(-1025 2050);
PAINT SKYBLUE (-1025 2050);
DISPLAY INVISIBLE (-1025 2050);
FORCEPROP 2 LAST CDS_LIB mstr_symbols
J 0
(-1025 2050);
PAINT ORANGE (-1025 2050);
DISPLAY INVISIBLE (-1025 2050);
FORCEPROP 1 LAST PATH I51
J 0
(-950 2050);
DISPLAY 0.872340 (-950 2050);
PAINT AQUA (-950 2050);
DISPLAY INVISIBLE (-950 2050);
FORCEPROP 1 LAST BODY_TYPE PLUMBING
J 0
(-1070 2007);
DISPLAY 0.340426 (-1070 2007);
PAINT GREEN (-1070 2007);
DISPLAY INVISIBLE (-1070 2007);
FORCEPROP 1 LAST HDL_POWER GND
J 0
(-1025 2200);
DISPLAY 1.170213 (-1025 2200);
PAINT GREEN (-1025 2200);
DISPLAY INVISIBLE (-1025 2200);
FORCEADD RES..2
(-925 1350);
FORCEPROP 1 LAST PACK_TYPE 0402
J 0
(-885 1175);
DISPLAY 0.617021 (-885 1175);
PAINT SKYBLUE (-885 1175);
FORCEPROP 1 LAST MATERIAL CHIP
J 0
(-885 1275);
DISPLAY 0.617021 (-885 1275);
PAINT SKYBLUE (-885 1275);
FORCEPROP 1 LAST TOLERANCE 1%
J 0
(-880 1375);
DISPLAY 0.617021 (-880 1375);
PAINT SKYBLUE (-880 1375);
FORCEPROP 1 LAST WATTAGE 1/16W
J 0
(-885 1325);
DISPLAY 0.617021 (-885 1325);
PAINT SKYBLUE (-885 1325);
FORCEPROP 1 LAST VALUE 3.16K
J 0
(-880 1425);
DISPLAY 0.617021 (-880 1425);
PAINT SKYBLUE (-880 1425);
FORCEPROP 1 LAST PART_NUMBER G21796-043
J 0
(-885 1225);
DISPLAY 0.617021 (-885 1225);
PAINT BLUE (-885 1225);
FORCEPROP 1 LAST LOCATION R3N31
J 0
(-880 1475);
DISPLAY 0.617021 (-880 1475);
PAINT AQUA (-880 1475);
FORCEPROP 1 LASTPIN (-925 1250) $PN 2
J 0
(-920 1260);
DISPLAY 0.787234 (-920 1260);
PAINT ORANGE (-920 1260);
DISPLAY INVISIBLE (-920 1260);
FORCEPROP 2 LAST CDS_LIB mstr_discrete
J 0
(-925 1350);
PAINT ORANGE (-925 1350);
DISPLAY INVISIBLE (-925 1350);
FORCEPROP 1 LASTPIN (-925 1450) $PN 1
J 0
(-920 1412);
DISPLAY 0.787234 (-920 1412);
PAINT ORANGE (-920 1412);
DISPLAY INVISIBLE (-920 1412);
FORCEPROP 1 LAST PATH I52
J 0
(-875 1525);
DISPLAY 0.978723 (-875 1525);
PAINT WHITE (-875 1525);
DISPLAY INVISIBLE (-875 1525);
FORCEPROP 0 LAST ROOM PVCCIO_CPU0
J 0
(-875 1575);
DISPLAY 1.021277 (-875 1575);
PAINT ORANGE (-875 1575);
DISPLAY INVISIBLE (-875 1575);
FORCEPROP 2 LAST $SEC 1
J 0
(-875 1575);
PAINT MONO (-875 1575);
DISPLAY INVISIBLE (-875 1575);
FORCEPROP 2 LAST CDS_SEC 1
J 0
(-875 1575);
PAINT MONO (-875 1575);
DISPLAY INVISIBLE (-875 1575);
FORCEADD GND..1
(-925 775);
FORCEPROP 3 LASTPIN (-925 825) SIG_NAME GND\g
J 0
(-915 835);
DISPLAY 0.659574 (-915 835);
PAINT MONO (-915 835);
DISPLAY INVISIBLE (-915 835);
FORCEPROP 2 LAST ROOM PVCCIO_CPU0
J 0
(-1500 850);
DISPLAY 1.361702 (-1500 850);
PAINT ORANGE (-1500 850);
DISPLAY INVISIBLE (-1500 850);
FORCEPROP 1 LAST VOLTAGE 0
J 0
(-925 775);
PAINT SKYBLUE (-925 775);
DISPLAY INVISIBLE (-925 775);
FORCEPROP 1 LAST SIZE 1B
J 0
(-850 725);
DISPLAY 1.170213 (-850 725);
PAINT AQUA (-850 725);
DISPLAY INVISIBLE (-850 725);
FORCEPROP 2 LAST CDS_LIB mstr_symbols
J 0
(-925 775);
PAINT ORANGE (-925 775);
DISPLAY INVISIBLE (-925 775);
FORCEPROP 1 LAST PATH I54
J 0
(-850 775);
DISPLAY 0.872340 (-850 775);
PAINT AQUA (-850 775);
DISPLAY INVISIBLE (-850 775);
FORCEPROP 1 LAST BODY_TYPE PLUMBING
J 0
(-970 732);
DISPLAY 0.340426 (-970 732);
PAINT GREEN (-970 732);
DISPLAY INVISIBLE (-970 732);
FORCEPROP 1 LAST HDL_POWER GND
J 0
(-925 925);
DISPLAY 1.170213 (-925 925);
PAINT GREEN (-925 925);
DISPLAY INVISIBLE (-925 925);
FORCEADD RES..2
(775 4100);
FORCEPROP 1 LAST PACK_TYPE 0402
J 0
(815 3925);
DISPLAY 0.617021 (815 3925);
PAINT SKYBLUE (815 3925);
FORCEPROP 1 LAST MATERIAL CHIP
J 0
(815 4025);
DISPLAY 0.617021 (815 4025);
PAINT SKYBLUE (815 4025);
FORCEPROP 1 LASTPIN (775 4000) $PN 2
J 0
(780 4010);
DISPLAY 0.617021 (780 4010);
PAINT ORANGE (780 4010);
FORCEPROP 1 LAST PART_NUMBER G21796-026
J 0
(815 3975);
DISPLAY 0.617021 (815 3975);
PAINT BLUE (815 3975);
FORCEPROP 1 LAST WATTAGE 1/16W
J 0
(815 4075);
DISPLAY 0.617021 (815 4075);
PAINT SKYBLUE (815 4075);
FORCEPROP 1 LAST LOCATION R3P25
J 0
(820 4225);
DISPLAY 0.617021 (820 4225);
PAINT AQUA (820 4225);
FORCEPROP 1 LAST VALUE 1.00K
J 0
(820 4175);
DISPLAY 0.617021 (820 4175);
PAINT SKYBLUE (820 4175);
FORCEPROP 1 LAST TOLERANCE 1%
J 0
(820 4125);
DISPLAY 0.617021 (820 4125);
PAINT SKYBLUE (820 4125);
FORCEPROP 1 LASTPIN (775 4200) $PN 1
J 0
(780 4162);
DISPLAY 0.617021 (780 4162);
PAINT ORANGE (780 4162);
FORCEPROP 1 LAST PATH I56
J 0
(825 4275);
DISPLAY 0.978723 (825 4275);
PAINT WHITE (825 4275);
DISPLAY INVISIBLE (825 4275);
FORCEPROP 2 LAST CDS_LOCATION R3P25
J 0
(820 4225);
DISPLAY 0.617021 (820 4225);
PAINT AQUA (820 4225);
DISPLAY INVISIBLE (820 4225);
FORCEPROP 2 LAST CDS_LIB mstr_discrete
J 0
(775 4100);
PAINT ORANGE (775 4100);
DISPLAY INVISIBLE (775 4100);
FORCEPROP 2 LAST ROOM PVCCIO_CPU0
J 0
(825 4275);
DISPLAY 1.361702 (825 4275);
PAINT ORANGE (825 4275);
DISPLAY INVISIBLE (825 4275);
FORCEPROP 0 LAST SEC 1
J 0
(825 4275);
DISPLAY 0.680851 (825 4275);
PAINT MONO (825 4275);
DISPLAY INVISIBLE (825 4275);
FORCEPROP 2 LAST SEC_TYPE 0402
J 0
(825 4325);
DISPLAY 1.021277 (825 4325);
PAINT ORANGE (825 4325);
DISPLAY INVISIBLE (825 4325);
FORCEADD OFFPAGE..2
(2700 3600);
FORCEPROP 2 LAST $XR0 118 
J 0
(2889 3600);
DISPLAY 0.638298 (2889 3600);
PAINT MONO (2889 3600);
FORCEPROP 2 LAST $XR1 190 
J 0
(3009 3600);
DISPLAY 0.638298 (3009 3600);
PAINT MONO (3009 3600);
FORCEPROP 2 LAST ROOM PVCCIO_CPU0
J 0
(2275 3675);
DISPLAY 1.361702 (2275 3675);
PAINT ORANGE (2275 3675);
DISPLAY INVISIBLE (2275 3675);
FORCEPROP 2 LAST PATH I57
J 0
(2875 3675);
DISPLAY 1.021277 (2875 3675);
PAINT ORANGE (2875 3675);
DISPLAY INVISIBLE (2875 3675);
FORCEPROP 2 LAST CDS_LIB mstr_standard
J 0
(2700 3600);
PAINT ORANGE (2700 3600);
DISPLAY INVISIBLE (2700 3600);
FORCEPROP 1 LAST OFFPAGE TRUE
J 0
(3025 3475);
DISPLAY 1.170213 (3025 3475);
PAINT GREEN (3025 3475);
DISPLAY INVISIBLE (3025 3475);
FORCEPROP 1 LAST COMMENT_BODY TRUE
J 0
(2655 3505);
DISPLAY 1.170213 (2655 3505);
PAINT GREEN (2655 3505);
DISPLAY INVISIBLE (2655 3505);
FORCEADD RES..1
(1875 3600);
FORCEPROP 1 LAST WATTAGE 1/16W
J 2
(1850 3450);
DISPLAY 0.617021 (1850 3450);
PAINT SKYBLUE (1850 3450);
FORCEPROP 1 LAST MATERIAL CHIP
J 0
(1875 3450);
DISPLAY 0.617021 (1875 3450);
PAINT SKYBLUE (1875 3450);
FORCEPROP 1 LAST TOLERANCE 1.0%
J 0
(1875 3500);
DISPLAY 0.617021 (1875 3500);
PAINT SKYBLUE (1875 3500);
FORCEPROP 1 LAST VALUE 22.1
J 2
(1850 3500);
DISPLAY 0.617021 (1850 3500);
PAINT SKYBLUE (1850 3500);
FORCEPROP 1 LASTPIN (1775 3600) $PN 1
J 0
(1787 3612);
DISPLAY 0.617021 (1787 3612);
PAINT ORANGE (1787 3612);
FORCEPROP 1 LAST LOCATION R3P20
J 0
(1825 3650);
DISPLAY 0.617021 (1825 3650);
PAINT AQUA (1825 3650);
FORCEPROP 1 LASTPIN (1975 3600) $PN 2
J 0
(1937 3612);
DISPLAY 0.617021 (1937 3612);
PAINT ORANGE (1937 3612);
FORCEPROP 1 LAST PART_NUMBER G21796-250
J 0
(1825 3700);
DISPLAY 0.617021 (1825 3700);
PAINT BLUE (1825 3700);
FORCEPROP 1 LAST PACK_TYPE 0402
J 0
(2125 3450);
DISPLAY 0.617021 (2125 3450);
PAINT SKYBLUE (2125 3450);
FORCEPROP 1 LAST PATH I58
J 0
(1825 3750);
DISPLAY 0.978723 (1825 3750);
PAINT WHITE (1825 3750);
DISPLAY INVISIBLE (1825 3750);
FORCEPROP 2 LAST CDS_LOCATION R3P20
J 0
(1825 3650);
DISPLAY 0.617021 (1825 3650);
PAINT AQUA (1825 3650);
DISPLAY INVISIBLE (1825 3650);
FORCEPROP 2 LAST SEC 1
J 0
(1825 3800);
DISPLAY 0.680851 (1825 3800);
PAINT MONO (1825 3800);
DISPLAY INVISIBLE (1825 3800);
FORCEPROP 2 LAST CDS_LIB mstr_discrete
J 0
(1875 3600);
PAINT MONO (1875 3600);
DISPLAY INVISIBLE (1875 3600);
FORCEPROP 2 LAST ROOM PVCCIO_CPU0
J 0
(1825 3700);
DISPLAY 1.361702 (1825 3700);
PAINT ORANGE (1825 3700);
DISPLAY INVISIBLE (1825 3700);
FORCEPROP 2 LAST SEC_TYPE 0402
J 0
(1825 3800);
DISPLAY 1.021277 (1825 3800);
PAINT ORANGE (1825 3800);
DISPLAY INVISIBLE (1825 3800);
FORCEADD P3V3_STBY..1
(1800 4775);
FORCEPROP 3 LASTPIN (1800 4725) SIG_NAME P3V3_STBY\g
J 0
(1810 4735);
DISPLAY 0.659574 (1810 4735);
PAINT MONO (1810 4735);
DISPLAY INVISIBLE (1810 4735);
FORCEPROP 1 LAST PATH I59
J 0
(1845 4777);
DISPLAY 0.340426 (1845 4777);
PAINT GREEN (1845 4777);
DISPLAY INVISIBLE (1845 4777);
FORCEPROP 1 LAST SIZE 1B
J 0
(1845 4797);
DISPLAY 0.340426 (1845 4797);
PAINT GREEN (1845 4797);
DISPLAY INVISIBLE (1845 4797);
FORCEPROP 2 LAST CDS_LIB mstr_symbols
J 0
(1800 4775);
PAINT ORANGE (1800 4775);
DISPLAY INVISIBLE (1800 4775);
FORCEPROP 1 LAST VOLTAGE 3.3V
J 0
(1755 4732);
DISPLAY 0.340426 (1755 4732);
PAINT SKYBLUE (1755 4732);
DISPLAY INVISIBLE (1755 4732);
FORCEPROP 1 LAST BODY_TYPE PLUMBING
J 0
(1755 4732);
DISPLAY 0.340426 (1755 4732);
PAINT GREEN (1755 4732);
DISPLAY INVISIBLE (1755 4732);
FORCEPROP 1 LAST HDL_POWER P3V3_STBY
J 0
(1500 4650);
DISPLAY 0.872340 (1500 4650);
PAINT ORANGE (1500 4650);
DISPLAY INVISIBLE (1500 4650);
FORCEADD OFFPAGE..1
R 2
(3025 1600);
FORCEPROP 2 LAST $XR0 211 
J 0
(3211 1600);
DISPLAY 0.638298 (3211 1600);
PAINT MONO (3211 1600);
FORCEPROP 2 LAST CDS_LIB mstr_standard
J 2
(3025 1600);
PAINT ORANGE (3025 1600);
DISPLAY INVISIBLE (3025 1600);
FORCEPROP 2 LAST ROOM PVCCIO_CPU0
J 0
(2600 1675);
DISPLAY 1.361702 (2600 1675);
PAINT ORANGE (2600 1675);
DISPLAY INVISIBLE (2600 1675);
FORCEPROP 2 LAST PATH I6
J 0
(3350 1650);
DISPLAY 1.021277 (3350 1650);
PAINT ORANGE (3350 1650);
DISPLAY INVISIBLE (3350 1650);
FORCEPROP 1 LAST OFFPAGE TRUE
J 2
(2700 1475);
DISPLAY 1.170213 (2700 1475);
PAINT GREEN (2700 1475);
DISPLAY INVISIBLE (2700 1475);
FORCEPROP 1 LAST COMMENT_BODY TRUE
J 2
(2900 1500);
DISPLAY 1.170213 (2900 1500);
PAINT GREEN (2900 1500);
DISPLAY INVISIBLE (2900 1500);
FORCEADD RES..2
(1525 4100);
FORCEPROP 1 LASTPIN (1525 4000) $PN 2
J 0
(1530 4010);
DISPLAY 0.617021 (1530 4010);
PAINT ORANGE (1530 4010);
FORCEPROP 1 LAST MATERIAL EMPTY
J 0
(1565 4025);
DISPLAY 0.617021 (1565 4025);
PAINT RED (1565 4025);
FORCEPROP 1 LAST PACK_TYPE 0402
J 0
(1565 3925);
DISPLAY 0.617021 (1565 3925);
PAINT SKYBLUE (1565 3925);
FORCEPROP 1 LAST PART_NUMBER G21796-311
J 0
(1565 3975);
DISPLAY 0.617021 (1565 3975);
PAINT BLUE (1565 3975);
FORCEPROP 1 LAST WATTAGE 1/16W
J 0
(1565 4075);
DISPLAY 0.617021 (1565 4075);
PAINT SKYBLUE (1565 4075);
FORCEPROP 1 LASTPIN (1525 4200) $PN 1
J 0
(1530 4162);
DISPLAY 0.617021 (1530 4162);
PAINT ORANGE (1530 4162);
FORCEPROP 1 LAST LOCATION R3N23
J 0
(1570 4225);
DISPLAY 0.617021 (1570 4225);
PAINT AQUA (1570 4225);
FORCEPROP 1 LAST VALUE 2.26K
J 0
(1570 4175);
DISPLAY 0.617021 (1570 4175);
PAINT SKYBLUE (1570 4175);
FORCEPROP 1 LAST TOLERANCE 1.0%
J 0
(1570 4125);
DISPLAY 0.617021 (1570 4125);
PAINT SKYBLUE (1570 4125);
FORCEPROP 2 LAST ROOM PVCCIO_CPU0
J 0
(1575 4075);
DISPLAY 1.361702 (1575 4075);
PAINT ORANGE (1575 4075);
DISPLAY INVISIBLE (1575 4075);
FORCEPROP 2 LAST CDS_LIB mstr_discrete
J 0
(1525 4100);
PAINT ORANGE (1525 4100);
DISPLAY INVISIBLE (1525 4100);
FORCEPROP 2 LAST SEC_TYPE 0402
J 0
(1575 4350);
DISPLAY 1.021277 (1575 4350);
PAINT ORANGE (1575 4350);
DISPLAY INVISIBLE (1575 4350);
FORCEPROP 1 LAST PATH I60
J 0
(1575 4275);
DISPLAY 0.978723 (1575 4275);
PAINT WHITE (1575 4275);
DISPLAY INVISIBLE (1575 4275);
FORCEPROP 2 LAST CDS_LOCATION R3N23
J 0
(1570 4225);
DISPLAY 0.617021 (1570 4225);
PAINT AQUA (1570 4225);
DISPLAY INVISIBLE (1570 4225);
FORCEPROP 2 LAST SEC 1
J 0
(1575 4350);
DISPLAY 0.680851 (1575 4350);
PAINT MONO (1575 4350);
DISPLAY INVISIBLE (1575 4350);
FORCEADD RES..1
(1300 3150);
FORCEPROP 1 LAST PART_NUMBER G21497-005
J 0
(1150 3050);
DISPLAY 0.617021 (1150 3050);
PAINT BLUE (1150 3050);
FORCEPROP 1 LAST VALUE 0.0
J 2
(1275 3100);
DISPLAY 0.617021 (1275 3100);
PAINT SKYBLUE (1275 3100);
FORCEPROP 1 LAST WATTAGE 1/16W
J 2
(1200 3100);
DISPLAY 0.617021 (1200 3100);
PAINT SKYBLUE (1200 3100);
FORCEPROP 1 LASTPIN (1200 3150) $PN 1
J 0
(1212 3162);
DISPLAY 0.617021 (1212 3162);
PAINT ORANGE (1212 3162);
FORCEPROP 1 LAST LOCATION R3P1
J 0
(1250 3200);
DISPLAY 0.617021 (1250 3200);
PAINT AQUA (1250 3200);
FORCEPROP 1 LASTPIN (1400 3150) $PN 2
J 0
(1362 3162);
DISPLAY 0.617021 (1362 3162);
PAINT ORANGE (1362 3162);
FORCEPROP 1 LAST TOLERANCE 5%
J 0
(1300 3100);
DISPLAY 0.617021 (1300 3100);
PAINT SKYBLUE (1300 3100);
FORCEPROP 1 LAST PACK_TYPE 0402
J 0
(1400 3100);
DISPLAY 0.617021 (1400 3100);
PAINT SKYBLUE (1400 3100);
FORCEPROP 1 LAST MATERIAL CHIP
J 0
(1525 3100);
DISPLAY 0.617021 (1525 3100);
PAINT SKYBLUE (1525 3100);
FORCEPROP 2 LAST SEC_TYPE 0402
J 0
(1250 3375);
DISPLAY 1.021277 (1250 3375);
PAINT ORANGE (1250 3375);
DISPLAY INVISIBLE (1250 3375);
FORCEPROP 1 LAST PATH I61
J 0
(1250 3300);
DISPLAY 0.978723 (1250 3300);
PAINT WHITE (1250 3300);
DISPLAY INVISIBLE (1250 3300);
FORCEPROP 2 LAST CDS_LOCATION R3P1
J 0
(1250 3200);
DISPLAY 0.617021 (1250 3200);
PAINT AQUA (1250 3200);
DISPLAY INVISIBLE (1250 3200);
FORCEPROP 2 LAST SEC 1
J 0
(1250 3375);
DISPLAY 0.680851 (1250 3375);
PAINT MONO (1250 3375);
DISPLAY INVISIBLE (1250 3375);
FORCEPROP 2 LAST ROOM PVCCIO_CPU0
J 0
(1250 3250);
DISPLAY 1.361702 (1250 3250);
PAINT ORANGE (1250 3250);
DISPLAY INVISIBLE (1250 3250);
FORCEPROP 2 LAST CDS_LIB mstr_discrete
J 0
(1300 3150);
PAINT ORANGE (1300 3150);
DISPLAY INVISIBLE (1300 3150);
FORCEADD OFFPAGE..2
(2700 3150);
FORCEPROP 2 LAST $XR0 194 
J 0
(2889 3150);
DISPLAY 0.638298 (2889 3150);
PAINT MONO (2889 3150);
FORCEPROP 2 LAST $XR1 201 
J 0
(3009 3150);
DISPLAY 0.638298 (3009 3150);
PAINT MONO (3009 3150);
FORCEPROP 2 LAST $XR2 21 
J 0
(3129 3150);
DISPLAY 0.638298 (3129 3150);
PAINT MONO (3129 3150);
FORCEPROP 2 LAST ROOM PVCCIO_CPU0
J 0
(2275 3225);
DISPLAY 1.361702 (2275 3225);
PAINT ORANGE (2275 3225);
DISPLAY INVISIBLE (2275 3225);
FORCEPROP 2 LAST CDS_LIB mstr_standard
J 0
(2700 3150);
PAINT ORANGE (2700 3150);
DISPLAY INVISIBLE (2700 3150);
FORCEPROP 2 LAST PATH I62
J 0
(3375 3200);
DISPLAY 1.021277 (3375 3200);
PAINT ORANGE (3375 3200);
DISPLAY INVISIBLE (3375 3200);
FORCEPROP 1 LAST OFFPAGE TRUE
J 0
(3025 3025);
DISPLAY 1.170213 (3025 3025);
PAINT GREEN (3025 3025);
DISPLAY INVISIBLE (3025 3025);
FORCEPROP 1 LAST COMMENT_BODY TRUE
J 0
(2655 3055);
DISPLAY 1.170213 (2655 3055);
PAINT GREEN (2655 3055);
DISPLAY INVISIBLE (2655 3055);
FORCEADD RES..2
(2075 4050);
FORCEPROP 1 LASTPIN (2075 3950) $PN 2
J 0
(2080 3960);
DISPLAY 0.617021 (2080 3960);
PAINT ORANGE (2080 3960);
FORCEPROP 1 LAST PACK_TYPE 0402
J 0
(2115 3875);
DISPLAY 0.617021 (2115 3875);
PAINT SKYBLUE (2115 3875);
FORCEPROP 1 LAST MATERIAL CHIP
J 0
(2115 3975);
DISPLAY 0.617021 (2115 3975);
PAINT SKYBLUE (2115 3975);
FORCEPROP 1 LAST WATTAGE 1/16W
J 0
(2115 4025);
DISPLAY 0.617021 (2115 4025);
PAINT SKYBLUE (2115 4025);
FORCEPROP 1 LAST PART_NUMBER G21796-026
J 0
(2115 3925);
DISPLAY 0.617021 (2115 3925);
PAINT BLUE (2115 3925);
FORCEPROP 1 LAST TOLERANCE 1%
J 0
(2120 4075);
DISPLAY 0.617021 (2120 4075);
PAINT SKYBLUE (2120 4075);
FORCEPROP 1 LAST LOCATION R3P18
J 0
(2120 4175);
DISPLAY 0.617021 (2120 4175);
PAINT AQUA (2120 4175);
FORCEPROP 1 LAST VALUE 1.00K
J 0
(2120 4125);
DISPLAY 0.617021 (2120 4125);
PAINT SKYBLUE (2120 4125);
FORCEPROP 1 LASTPIN (2075 4150) $PN 1
J 0
(2080 4112);
DISPLAY 0.617021 (2080 4112);
PAINT ORANGE (2080 4112);
FORCEPROP 2 LAST CDS_LIB mstr_discrete
J 0
(2075 4050);
PAINT ORANGE (2075 4050);
DISPLAY INVISIBLE (2075 4050);
FORCEPROP 1 LAST PATH I64
J 0
(2125 4225);
DISPLAY 0.978723 (2125 4225);
PAINT WHITE (2125 4225);
DISPLAY INVISIBLE (2125 4225);
FORCEPROP 2 LAST CDS_LOCATION R3P18
J 0
(2120 4175);
DISPLAY 0.617021 (2120 4175);
PAINT AQUA (2120 4175);
DISPLAY INVISIBLE (2120 4175);
FORCEPROP 2 LAST SEC 1
J 0
(2125 4275);
DISPLAY 0.680851 (2125 4275);
PAINT MONO (2125 4275);
DISPLAY INVISIBLE (2125 4275);
FORCEPROP 2 LAST SEC_TYPE 0402
J 0
(2125 4275);
DISPLAY 1.021277 (2125 4275);
PAINT ORANGE (2125 4275);
DISPLAY INVISIBLE (2125 4275);
FORCEADD RES..2
(-575 1375);
FORCEPROP 1 LAST WATTAGE 1/16W
J 0
(-535 1350);
DISPLAY 0.617021 (-535 1350);
PAINT SKYBLUE (-535 1350);
FORCEPROP 1 LAST MATERIAL CHIP
J 0
(-535 1300);
DISPLAY 0.617021 (-535 1300);
PAINT SKYBLUE (-535 1300);
FORCEPROP 1 LAST PACK_TYPE 0402
J 0
(-535 1200);
DISPLAY 0.617021 (-535 1200);
PAINT SKYBLUE (-535 1200);
FORCEPROP 1 LAST TOLERANCE 1%
J 0
(-530 1400);
DISPLAY 0.617021 (-530 1400);
PAINT SKYBLUE (-530 1400);
FORCEPROP 1 LAST VALUE 4.02K
J 0
(-530 1450);
DISPLAY 0.617021 (-530 1450);
PAINT SKYBLUE (-530 1450);
FORCEPROP 1 LAST PART_NUMBER G21796-082
J 0
(-535 1250);
DISPLAY 0.617021 (-535 1250);
PAINT BLUE (-535 1250);
FORCEPROP 1 LAST LOCATION R3N22
J 0
(-530 1500);
DISPLAY 0.617021 (-530 1500);
PAINT AQUA (-530 1500);
FORCEPROP 2 LAST CDS_LIB mstr_discrete
J 0
(-575 1375);
PAINT ORANGE (-575 1375);
DISPLAY INVISIBLE (-575 1375);
FORCEPROP 2 LAST CDS_LOCATION R3N22
J 0
(-530 1500);
DISPLAY 0.617021 (-530 1500);
PAINT AQUA (-530 1500);
DISPLAY INVISIBLE (-530 1500);
FORCEPROP 1 LASTPIN (-575 1275) $PN 2
J 0
(-570 1285);
DISPLAY 0.787234 (-570 1285);
PAINT ORANGE (-570 1285);
DISPLAY INVISIBLE (-570 1285);
FORCEPROP 1 LASTPIN (-575 1475) $PN 1
J 0
(-570 1437);
DISPLAY 0.787234 (-570 1437);
PAINT ORANGE (-570 1437);
DISPLAY INVISIBLE (-570 1437);
FORCEPROP 1 LAST PATH I65
J 0
(-525 1550);
DISPLAY 0.978723 (-525 1550);
PAINT WHITE (-525 1550);
DISPLAY INVISIBLE (-525 1550);
FORCEPROP 2 LAST $SEC 1
J 0
(-525 1600);
DISPLAY 0.680851 (-525 1600);
PAINT MONO (-525 1600);
DISPLAY INVISIBLE (-525 1600);
FORCEPROP 2 LAST CDS_SEC 1
J 0
(-525 1600);
DISPLAY 1.021277 (-525 1600);
PAINT ORANGE (-525 1600);
DISPLAY INVISIBLE (-525 1600);
FORCEADD CAP..1
(1650 2750);
FORCEPROP 1 LAST PACK_TYPE 0402LF
J 0
(1700 2550);
DISPLAY 0.617021 (1700 2550);
PAINT SKYBLUE (1700 2550);
FORCEPROP 1 LASTPIN (1650 2650) $PN 2
J 0
(1660 2630);
DISPLAY 0.617021 (1660 2630);
PAINT ORANGE (1660 2630);
FORCEPROP 1 LAST MATERIAL X7R
J 0
(1700 2650);
DISPLAY 0.617021 (1700 2650);
PAINT SKYBLUE (1700 2650);
FORCEPROP 1 LAST TOLERANCE 10%
J 0
(1700 2700);
DISPLAY 0.617021 (1700 2700);
PAINT SKYBLUE (1700 2700);
FORCEPROP 1 LAST VOLTAGE 50V
J 0
(1700 2750);
DISPLAY 0.617021 (1700 2750);
PAINT SKYBLUE (1700 2750);
FORCEPROP 1 LASTPIN (1650 2850) $PN 1
J 0
(1660 2830);
DISPLAY 0.617021 (1660 2830);
PAINT ORANGE (1660 2830);
FORCEPROP 1 LAST LOCATION C3P6
J 0
(1700 2850);
DISPLAY 0.617021 (1700 2850);
PAINT AQUA (1700 2850);
FORCEPROP 1 LAST PART_NUMBER A36096-046
J 0
(1700 2600);
DISPLAY 0.617021 (1700 2600);
PAINT BLUE (1700 2600);
FORCEPROP 1 LAST VALUE 1000PF
J 0
(1700 2800);
DISPLAY 0.617021 (1700 2800);
PAINT SKYBLUE (1700 2800);
FORCEPROP 2 LAST CDS_LIB mstr_discrete
J 0
(1650 2750);
PAINT MONO (1650 2750);
DISPLAY INVISIBLE (1650 2750);
FORCEPROP 2 LAST CDS_LOCATION C3P6
J 0
(1700 2850);
DISPLAY 0.617021 (1700 2850);
PAINT AQUA (1700 2850);
DISPLAY INVISIBLE (1700 2850);
FORCEPROP 1 LAST PATH I71
J 0
(1700 2900);
DISPLAY 0.978723 (1700 2900);
PAINT WHITE (1700 2900);
DISPLAY INVISIBLE (1700 2900);
FORCEPROP 2 LAST SEC_TYPE 0402LF
J 0
(1700 2950);
DISPLAY 1.021277 (1700 2950);
PAINT ORANGE (1700 2950);
DISPLAY INVISIBLE (1700 2950);
FORCEPROP 2 LAST SEC 1
J 0
(1700 2950);
DISPLAY 0.680851 (1700 2950);
PAINT MONO (1700 2950);
DISPLAY INVISIBLE (1700 2950);
FORCEPROP 0 LAST ROOM PVCCIO_CPU0_VR
J 0
(1700 2950);
DISPLAY 1.021277 (1700 2950);
PAINT ORANGE (1700 2950);
DISPLAY INVISIBLE (1700 2950);
FORCEADD GND..1
(1650 2475);
FORCEPROP 3 LASTPIN (1650 2525) SIG_NAME GND\g
J 0
(1660 2535);
DISPLAY 0.659574 (1660 2535);
PAINT MONO (1660 2535);
DISPLAY INVISIBLE (1660 2535);
FORCEPROP 2 LAST ROOM PVCCIO_CPU0
J 0
(1075 2550);
DISPLAY 1.361702 (1075 2550);
PAINT ORANGE (1075 2550);
DISPLAY INVISIBLE (1075 2550);
FORCEPROP 1 LAST PATH I72
J 0
(1725 2475);
DISPLAY 0.872340 (1725 2475);
PAINT AQUA (1725 2475);
DISPLAY INVISIBLE (1725 2475);
FORCEPROP 1 LAST SIZE 1B
J 0
(1725 2425);
DISPLAY 1.170213 (1725 2425);
PAINT AQUA (1725 2425);
DISPLAY INVISIBLE (1725 2425);
FORCEPROP 2 LAST CDS_LIB mstr_symbols
J 0
(1650 2475);
PAINT MONO (1650 2475);
DISPLAY INVISIBLE (1650 2475);
FORCEPROP 1 LAST VOLTAGE 0
J 0
(1650 2475);
PAINT SKYBLUE (1650 2475);
DISPLAY INVISIBLE (1650 2475);
FORCEPROP 1 LAST BODY_TYPE PLUMBING
J 0
(1605 2432);
DISPLAY 0.340426 (1605 2432);
PAINT GREEN (1605 2432);
DISPLAY INVISIBLE (1605 2432);
FORCEPROP 1 LAST HDL_POWER GND
J 0
(1650 2625);
DISPLAY 1.170213 (1650 2625);
PAINT GREEN (1650 2625);
DISPLAY INVISIBLE (1650 2625);
FORCEADD RES..1
(-2600 2050);
FORCEPROP 1 LAST WATTAGE 1/16W
J 2
(-2600 1900);
DISPLAY 0.617021 (-2600 1900);
PAINT SKYBLUE (-2600 1900);
FORCEPROP 1 LAST TOLERANCE 1%
J 0
(-2675 1950);
DISPLAY 0.617021 (-2675 1950);
PAINT SKYBLUE (-2675 1950);
FORCEPROP 1 LAST VALUE 10.0
J 2
(-2700 1950);
DISPLAY 0.617021 (-2700 1950);
PAINT SKYBLUE (-2700 1950);
FORCEPROP 1 LAST MATERIAL CHIP
J 0
(-2575 1900);
DISPLAY 0.617021 (-2575 1900);
PAINT SKYBLUE (-2575 1900);
FORCEPROP 1 LAST PACK_TYPE 0402
J 0
(-2575 1950);
DISPLAY 0.617021 (-2575 1950);
PAINT SKYBLUE (-2575 1950);
FORCEPROP 1 LAST PART_NUMBER G21796-066
J 0
(-2750 2000);
DISPLAY 0.617021 (-2750 2000);
PAINT BLUE (-2750 2000);
FORCEPROP 1 LAST LOCATION R3N19
J 0
(-2650 2100);
DISPLAY 0.617021 (-2650 2100);
PAINT AQUA (-2650 2100);
FORCEPROP 1 LASTPIN (-2700 2050) $PN 1
J 0
(-2688 2062);
DISPLAY 0.617021 (-2688 2062);
PAINT ORANGE (-2688 2062);
DISPLAY INVISIBLE (-2688 2062);
FORCEPROP 1 LAST PATH I81
J 0
(-2650 2200);
DISPLAY 0.978723 (-2650 2200);
PAINT WHITE (-2650 2200);
DISPLAY INVISIBLE (-2650 2200);
FORCEPROP 2 LAST CDS_LOCATION R3N19
J 0
(-2650 2100);
DISPLAY 0.617021 (-2650 2100);
PAINT AQUA (-2650 2100);
DISPLAY INVISIBLE (-2650 2100);
FORCEPROP 2 LAST $SEC 1
J 0
(-2650 2250);
DISPLAY 0.680851 (-2650 2250);
PAINT MONO (-2650 2250);
DISPLAY INVISIBLE (-2650 2250);
FORCEPROP 2 LAST CDS_SEC 1
J 0
(-2650 2250);
DISPLAY 1.021277 (-2650 2250);
PAINT ORANGE (-2650 2250);
DISPLAY INVISIBLE (-2650 2250);
FORCEPROP 2 LAST CDS_LIB mstr_discrete
J 0
(-2600 2050);
PAINT ORANGE (-2600 2050);
DISPLAY INVISIBLE (-2600 2050);
FORCEPROP 2 LAST ROOM PVCCIO_CPU0
J 0
(-2525 2150);
DISPLAY 1.361702 (-2525 2150);
PAINT ORANGE (-2525 2150);
DISPLAY INVISIBLE (-2525 2150);
FORCEPROP 1 LASTPIN (-2500 2050) $PN 2
J 0
(-2538 2062);
DISPLAY 0.617021 (-2538 2062);
PAINT ORANGE (-2538 2062);
DISPLAY INVISIBLE (-2538 2062);
FORCEADD OFFPAGE..1
(-3425 2050);
FORCEPROP 2 LAST $XR0 212 
J 0
(-3707 2050);
DISPLAY 0.638298 (-3707 2050);
PAINT MONO (-3707 2050);
FORCEPROP 2 LAST ROOM PVCCIO_CPU0
J 0
(-3975 2125);
DISPLAY 1.361702 (-3975 2125);
PAINT ORANGE (-3975 2125);
DISPLAY INVISIBLE (-3975 2125);
FORCEPROP 2 LAST PATH I82
J 0
(-3700 2100);
DISPLAY 1.021277 (-3700 2100);
PAINT ORANGE (-3700 2100);
DISPLAY INVISIBLE (-3700 2100);
FORCEPROP 2 LAST CDS_LIB mstr_standard
J 0
(-3425 2050);
PAINT ORANGE (-3425 2050);
DISPLAY INVISIBLE (-3425 2050);
FORCEPROP 1 LAST OFFPAGE TRUE
J 0
(-3100 1925);
DISPLAY 1.170213 (-3100 1925);
PAINT GREEN (-3100 1925);
DISPLAY INVISIBLE (-3100 1925);
FORCEPROP 1 LAST COMMENT_BODY TRUE
J 0
(-3300 1950);
DISPLAY 1.170213 (-3300 1950);
PAINT GREEN (-3300 1950);
DISPLAY INVISIBLE (-3300 1950);
FORCEADD CAP..1
(-2400 1850);
FORCEPROP 1 LASTPIN (-2400 1750) $PN 2
J 0
(-2390 1730);
DISPLAY 0.617021 (-2390 1730);
PAINT ORANGE (-2390 1730);
FORCEPROP 1 LASTPIN (-2400 1950) $PN 1
J 0
(-2390 1930);
DISPLAY 0.617021 (-2390 1930);
PAINT ORANGE (-2390 1930);
FORCEPROP 1 LAST LOCATION C3N39
J 0
(-2350 1950);
DISPLAY 0.617021 (-2350 1950);
PAINT AQUA (-2350 1950);
FORCEPROP 1 LAST VOLTAGE 50V
J 0
(-2350 1850);
DISPLAY 0.617021 (-2350 1850);
PAINT SKYBLUE (-2350 1850);
FORCEPROP 1 LAST PACK_TYPE 0402LF
J 0
(-2350 1750);
DISPLAY 0.617021 (-2350 1750);
PAINT SKYBLUE (-2350 1750);
FORCEPROP 1 LAST PART_NUMBER A36096-050
J 0
(-2350 1800);
DISPLAY 0.617021 (-2350 1800);
PAINT BLUE (-2350 1800);
FORCEPROP 1 LAST VALUE 220PF
J 0
(-2350 1900);
DISPLAY 0.617021 (-2350 1900);
PAINT SKYBLUE (-2350 1900);
FORCEPROP 1 LAST TOLERANCE 10%
J 0
(-2200 1900);
DISPLAY 0.617021 (-2200 1900);
PAINT SKYBLUE (-2200 1900);
FORCEPROP 1 LAST MATERIAL X7R
J 0
(-2275 1850);
DISPLAY 0.617021 (-2275 1850);
PAINT SKYBLUE (-2275 1850);
FORCEPROP 2 LAST CDS_LIB mstr_discrete
J 0
(-2400 1850);
PAINT ORANGE (-2400 1850);
DISPLAY INVISIBLE (-2400 1850);
FORCEPROP 2 LAST CDS_LOCATION C3N39
J 0
(-2350 1950);
DISPLAY 0.617021 (-2350 1950);
PAINT AQUA (-2350 1950);
DISPLAY INVISIBLE (-2350 1950);
FORCEPROP 1 LAST PATH I83
J 0
(-2350 2000);
DISPLAY 0.978723 (-2350 2000);
PAINT WHITE (-2350 2000);
DISPLAY INVISIBLE (-2350 2000);
FORCEPROP 2 LAST ROOM PVCCIO_CPU0
J 0
(-2350 2000);
DISPLAY 1.361702 (-2350 2000);
PAINT ORANGE (-2350 2000);
DISPLAY INVISIBLE (-2350 2000);
FORCEPROP 2 LAST SEC_TYPE 0402LF
J 0
(-2350 2075);
DISPLAY 1.021277 (-2350 2075);
PAINT ORANGE (-2350 2075);
DISPLAY INVISIBLE (-2350 2075);
FORCEPROP 2 LAST SEC 1
J 0
(-2350 2075);
DISPLAY 0.680851 (-2350 2075);
PAINT MONO (-2350 2075);
DISPLAY INVISIBLE (-2350 2075);
FORCEADD OFFPAGE..1
(-3350 1650);
FORCEPROP 2 LAST $XR0 212 
J 0
(-3602 1650);
DISPLAY 0.638298 (-3602 1650);
PAINT MONO (-3602 1650);
FORCEPROP 2 LAST PATH I84
J 0
(-3625 1700);
DISPLAY 1.021277 (-3625 1700);
PAINT ORANGE (-3625 1700);
DISPLAY INVISIBLE (-3625 1700);
FORCEPROP 2 LAST ROOM PVCCIO_CPU0
J 0
(-3900 1725);
DISPLAY 1.361702 (-3900 1725);
PAINT ORANGE (-3900 1725);
DISPLAY INVISIBLE (-3900 1725);
FORCEPROP 2 LAST CDS_LIB mstr_standard
J 0
(-3350 1650);
PAINT ORANGE (-3350 1650);
DISPLAY INVISIBLE (-3350 1650);
FORCEPROP 1 LAST OFFPAGE TRUE
J 0
(-3025 1525);
DISPLAY 1.170213 (-3025 1525);
PAINT GREEN (-3025 1525);
DISPLAY INVISIBLE (-3025 1525);
FORCEPROP 1 LAST COMMENT_BODY TRUE
J 0
(-3225 1550);
DISPLAY 1.170213 (-3225 1550);
PAINT GREEN (-3225 1550);
DISPLAY INVISIBLE (-3225 1550);
FORCEADD RES..1
(-1950 3250);
FORCEPROP 1 LAST VALUE 0.0
J 2
(-2050 3150);
DISPLAY 0.617021 (-2050 3150);
PAINT SKYBLUE (-2050 3150);
FORCEPROP 1 LAST WATTAGE 1/16W
J 2
(-1975 3100);
DISPLAY 0.617021 (-1975 3100);
PAINT SKYBLUE (-1975 3100);
FORCEPROP 1 LAST PART_NUMBER G21497-005
J 0
(-2100 3200);
DISPLAY 0.617021 (-2100 3200);
PAINT BLUE (-2100 3200);
FORCEPROP 1 LAST TOLERANCE 5%
J 0
(-2000 3150);
DISPLAY 0.617021 (-2000 3150);
PAINT SKYBLUE (-2000 3150);
FORCEPROP 1 LAST LOCATION R3P26
J 0
(-2000 3300);
DISPLAY 0.617021 (-2000 3300);
PAINT AQUA (-2000 3300);
FORCEPROP 1 LAST MATERIAL CHIP
J 0
(-1950 3100);
DISPLAY 0.617021 (-1950 3100);
PAINT SKYBLUE (-1950 3100);
FORCEPROP 1 LAST PACK_TYPE 0402
J 0
(-1875 3150);
DISPLAY 0.617021 (-1875 3150);
PAINT SKYBLUE (-1875 3150);
FORCEPROP 1 LASTPIN (-2050 3250) $PN 1
J 0
(-2038 3262);
DISPLAY 0.787234 (-2038 3262);
PAINT ORANGE (-2038 3262);
DISPLAY INVISIBLE (-2038 3262);
FORCEPROP 2 LAST CDS_LIB mstr_discrete
J 0
(-1950 3250);
PAINT ORANGE (-1950 3250);
DISPLAY INVISIBLE (-1950 3250);
FORCEPROP 2 LAST CDS_LOCATION R3P26
J 0
(-2000 3300);
DISPLAY 0.617021 (-2000 3300);
PAINT AQUA (-2000 3300);
DISPLAY INVISIBLE (-2000 3300);
FORCEPROP 1 LASTPIN (-1850 3250) $PN 2
J 0
(-1888 3262);
DISPLAY 0.787234 (-1888 3262);
PAINT ORANGE (-1888 3262);
DISPLAY INVISIBLE (-1888 3262);
FORCEPROP 2 LAST ROOM PVCCIN_CPU0_VR
J 0
(-2000 3350);
DISPLAY 1.361702 (-2000 3350);
PAINT ORANGE (-2000 3350);
DISPLAY INVISIBLE (-2000 3350);
FORCEPROP 1 LAST PATH I87
J 0
(-2000 3400);
DISPLAY 0.978723 (-2000 3400);
PAINT WHITE (-2000 3400);
DISPLAY INVISIBLE (-2000 3400);
FORCEPROP 2 LAST CDS_SEC 1
J 0
(-2000 3450);
PAINT MONO (-2000 3450);
DISPLAY INVISIBLE (-2000 3450);
FORCEPROP 2 LAST $SEC 1
J 0
(-2000 3450);
PAINT MONO (-2000 3450);
DISPLAY INVISIBLE (-2000 3450);
FORCEADD RES..2
(-1125 4300);
FORCEPROP 1 LAST WATTAGE 1/16W
J 0
(-1085 4275);
DISPLAY 0.617021 (-1085 4275);
PAINT SKYBLUE (-1085 4275);
FORCEPROP 1 LAST PACK_TYPE 0402
J 0
(-1085 4125);
DISPLAY 0.617021 (-1085 4125);
PAINT SKYBLUE (-1085 4125);
FORCEPROP 1 LAST TOLERANCE 1%
J 0
(-1080 4325);
DISPLAY 0.617021 (-1080 4325);
PAINT SKYBLUE (-1080 4325);
FORCEPROP 1 LAST VALUE 100.0K
J 0
(-1080 4375);
DISPLAY 0.617021 (-1080 4375);
PAINT SKYBLUE (-1080 4375);
FORCEPROP 1 LAST PART_NUMBER G21796-010
J 0
(-1085 4175);
DISPLAY 0.617021 (-1085 4175);
PAINT BLUE (-1085 4175);
FORCEPROP 1 LAST LOCATION R3P21
J 0
(-1080 4425);
DISPLAY 0.617021 (-1080 4425);
PAINT AQUA (-1080 4425);
FORCEPROP 1 LAST MATERIAL EMPTY
J 0
(-1085 4225);
DISPLAY 0.617021 (-1085 4225);
PAINT RED (-1085 4225);
FORCEPROP 1 LASTPIN (-1125 4200) $PN 2
J 0
(-1120 4210);
DISPLAY 0.787234 (-1120 4210);
PAINT ORANGE (-1120 4210);
DISPLAY INVISIBLE (-1120 4210);
FORCEPROP 2 LAST CDS_LIB mstr_discrete
J 0
(-1125 4300);
PAINT ORANGE (-1125 4300);
DISPLAY INVISIBLE (-1125 4300);
FORCEPROP 1 LASTPIN (-1125 4400) $PN 1
J 0
(-1120 4362);
DISPLAY 0.787234 (-1120 4362);
PAINT ORANGE (-1120 4362);
DISPLAY INVISIBLE (-1120 4362);
FORCEPROP 0 LAST ROOM BMC
J 0
(-1075 4525);
DISPLAY 0.617021 (-1075 4525);
PAINT ORANGE (-1075 4525);
DISPLAY INVISIBLE (-1075 4525);
FORCEPROP 1 LAST PATH I88
J 0
(-1075 4475);
DISPLAY 0.978723 (-1075 4475);
PAINT WHITE (-1075 4475);
DISPLAY INVISIBLE (-1075 4475);
FORCEPROP 2 LAST CDS_LOCATION R3P21
J 0
(-1080 4425);
DISPLAY 0.617021 (-1080 4425);
PAINT AQUA (-1080 4425);
DISPLAY INVISIBLE (-1080 4425);
FORCEPROP 2 LAST $SEC 1
J 0
(-1075 4525);
PAINT MONO (-1075 4525);
DISPLAY INVISIBLE (-1075 4525);
FORCEPROP 2 LAST CDS_SEC 1
J 0
(-1075 4525);
PAINT MONO (-1075 4525);
DISPLAY INVISIBLE (-1075 4525);
FORCEPROP 0 LAST BOM_COST SM_CONTROLLER
J 0
(-1075 4625);
DISPLAY 1.021277 (-1075 4625);
PAINT ORANGE (-1075 4625);
DISPLAY INVISIBLE (-1075 4625);
FORCEADD RES..1
(-2450 3750);
FORCEPROP 1 LAST WATTAGE 1/16W
J 2
(-2475 3600);
DISPLAY 0.617021 (-2475 3600);
PAINT SKYBLUE (-2475 3600);
FORCEPROP 1 LAST VALUE 0.0
J 2
(-2550 3650);
DISPLAY 0.617021 (-2550 3650);
PAINT SKYBLUE (-2550 3650);
FORCEPROP 1 LAST PART_NUMBER G21497-005
J 0
(-2600 3700);
DISPLAY 0.617021 (-2600 3700);
PAINT BLUE (-2600 3700);
FORCEPROP 1 LAST TOLERANCE 5%
J 0
(-2500 3650);
DISPLAY 0.617021 (-2500 3650);
PAINT SKYBLUE (-2500 3650);
FORCEPROP 1 LAST LOCATION R3P57
J 0
(-2500 3800);
DISPLAY 0.617021 (-2500 3800);
PAINT AQUA (-2500 3800);
FORCEPROP 1 LAST MATERIAL CHIP
J 0
(-2450 3600);
DISPLAY 0.617021 (-2450 3600);
PAINT SKYBLUE (-2450 3600);
FORCEPROP 1 LAST PACK_TYPE 0402
J 0
(-2375 3650);
DISPLAY 0.617021 (-2375 3650);
PAINT SKYBLUE (-2375 3650);
FORCEPROP 1 LASTPIN (-2550 3750) $PN 1
J 0
(-2538 3762);
DISPLAY 0.787234 (-2538 3762);
PAINT ORANGE (-2538 3762);
DISPLAY INVISIBLE (-2538 3762);
FORCEPROP 2 LAST CDS_LIB mstr_discrete
J 0
(-2450 3750);
PAINT ORANGE (-2450 3750);
DISPLAY INVISIBLE (-2450 3750);
FORCEPROP 1 LASTPIN (-2350 3750) $PN 2
J 0
(-2388 3762);
DISPLAY 0.787234 (-2388 3762);
PAINT ORANGE (-2388 3762);
DISPLAY INVISIBLE (-2388 3762);
FORCEPROP 2 LAST CDS_SEC 1
J 0
(-2500 3950);
PAINT MONO (-2500 3950);
DISPLAY INVISIBLE (-2500 3950);
FORCEPROP 2 LAST $SEC 1
J 0
(-2500 3950);
PAINT MONO (-2500 3950);
DISPLAY INVISIBLE (-2500 3950);
FORCEPROP 1 LAST PATH I91
J 0
(-2500 3900);
DISPLAY 0.978723 (-2500 3900);
PAINT WHITE (-2500 3900);
DISPLAY INVISIBLE (-2500 3900);
FORCEPROP 2 LAST ROOM PVCCIN_CPU0_VR
J 0
(-2500 3850);
DISPLAY 1.361702 (-2500 3850);
PAINT ORANGE (-2500 3850);
DISPLAY INVISIBLE (-2500 3850);
FORCEADD OFFPAGE..1
(-3275 3750);
FORCEPROP 2 LAST $XR0 211 
J 0
(-3527 3750);
DISPLAY 0.638298 (-3527 3750);
PAINT MONO (-3527 3750);
FORCEPROP 2 LAST ROOM PVCCIO_CPU0
J 0
(-3825 3825);
DISPLAY 1.361702 (-3825 3825);
PAINT ORANGE (-3825 3825);
DISPLAY INVISIBLE (-3825 3825);
FORCEPROP 2 LAST CDS_LIB mstr_standard
J 0
(-3275 3750);
PAINT ORANGE (-3275 3750);
DISPLAY INVISIBLE (-3275 3750);
FORCEPROP 2 LAST PATH I92
J 0
(-3225 3825);
DISPLAY 1.021277 (-3225 3825);
PAINT ORANGE (-3225 3825);
DISPLAY INVISIBLE (-3225 3825);
FORCEPROP 1 LAST OFFPAGE TRUE
J 0
(-2950 3625);
DISPLAY 1.170213 (-2950 3625);
PAINT GREEN (-2950 3625);
DISPLAY INVISIBLE (-2950 3625);
FORCEPROP 1 LAST COMMENT_BODY TRUE
J 0
(-3150 3650);
DISPLAY 1.170213 (-3150 3650);
PAINT GREEN (-3150 3650);
DISPLAY INVISIBLE (-3150 3650);
FORCEADD PXE1110B..1
(100 2850);
FORCEPROP 1 LAST PART_NUMBER H89187-001
J 0
(-300 1950);
DISPLAY 0.617021 (-300 1950);
PAINT BLUE (-300 1950);
FORCEPROP 2 LASTPIN (-350 2050) $PN 33
J 2
(-360 2060);
DISPLAY 0.617021 (-360 2060);
PAINT ORANGE (-360 2060);
FORCEPROP 2 LASTPIN (-350 2100) $PN 36
J 2
(-360 2110);
DISPLAY 0.617021 (-360 2110);
PAINT ORANGE (-360 2110);
FORCEPROP 2 LASTPIN (-350 2150) $PN 26
J 2
(-360 2160);
DISPLAY 0.617021 (-360 2160);
PAINT ORANGE (-360 2160);
FORCEPROP 2 LASTPIN (-350 2200) $PN 25
J 2
(-360 2210);
DISPLAY 0.617021 (-360 2210);
PAINT ORANGE (-360 2210);
FORCEPROP 2 LASTPIN (-350 2300) $PN 34
J 2
(-360 2310);
DISPLAY 0.617021 (-360 2310);
PAINT ORANGE (-360 2310);
FORCEPROP 2 LASTPIN (-350 2400) $PN 7
J 2
(-360 2410);
DISPLAY 0.617021 (-360 2410);
PAINT ORANGE (-360 2410);
FORCEPROP 2 LASTPIN (-350 2450) $PN 6
J 2
(-360 2460);
DISPLAY 0.617021 (-360 2460);
PAINT ORANGE (-360 2460);
FORCEPROP 2 LASTPIN (-350 2550) $PN 30
J 2
(-360 2560);
DISPLAY 0.617021 (-360 2560);
PAINT ORANGE (-360 2560);
FORCEPROP 2 LASTPIN (-350 2650) $PN 20
J 2
(-360 2660);
DISPLAY 0.617021 (-360 2660);
PAINT ORANGE (-360 2660);
FORCEPROP 2 LASTPIN (-350 2700) $PN 19
J 2
(-360 2710);
DISPLAY 0.617021 (-360 2710);
PAINT ORANGE (-360 2710);
FORCEPROP 2 LASTPIN (-350 2600) $PN 29
J 2
(-360 2610);
DISPLAY 0.617021 (-360 2610);
PAINT ORANGE (-360 2610);
FORCEPROP 2 LASTPIN (-350 2800) $PN 8
J 2
(-360 2810);
DISPLAY 0.617021 (-360 2810);
PAINT ORANGE (-360 2810);
FORCEPROP 2 LASTPIN (-350 3000) $PN 40
J 2
(-360 3010);
DISPLAY 0.617021 (-360 3010);
PAINT ORANGE (-360 3010);
FORCEPROP 2 LASTPIN (-350 2950) $PN 16
J 2
(-360 2960);
DISPLAY 0.617021 (-360 2960);
PAINT ORANGE (-360 2960);
FORCEPROP 2 LASTPIN (-350 3250) $PN 10
J 2
(-360 3260);
DISPLAY 0.617021 (-360 3260);
PAINT ORANGE (-360 3260);
FORCEPROP 2 LASTPIN (-350 3100) $PN 38
J 2
(-360 3110);
DISPLAY 0.617021 (-360 3110);
PAINT ORANGE (-360 3110);
FORCEPROP 2 LASTPIN (-350 3150) $PN 37
J 2
(-360 3160);
DISPLAY 0.617021 (-360 3160);
PAINT ORANGE (-360 3160);
FORCEPROP 2 LASTPIN (-350 3300) $PN 35
J 2
(-360 3310);
DISPLAY 0.617021 (-360 3310);
PAINT ORANGE (-360 3310);
FORCEPROP 2 LASTPIN (-350 3450) $PN 21
J 2
(-360 3460);
DISPLAY 0.617021 (-360 3460);
PAINT ORANGE (-360 3460);
FORCEPROP 2 LASTPIN (-350 3400) $PN 22
J 2
(-360 3410);
DISPLAY 0.617021 (-360 3410);
PAINT ORANGE (-360 3410);
FORCEPROP 2 LASTPIN (-350 3550) $PN 15
J 2
(-360 3560);
DISPLAY 0.617021 (-360 3560);
PAINT ORANGE (-360 3560);
FORCEPROP 2 LASTPIN (-350 3600) $PN 39
J 2
(-360 3610);
DISPLAY 0.617021 (-360 3610);
PAINT ORANGE (-360 3610);
FORCEPROP 1 LAST LOCATION EU3P1
J 0
(-300 3775);
DISPLAY 0.617021 (-300 3775);
PAINT AQUA (-300 3775);
FORCEPROP 1 LAST MATERIAL IC
J 0
(-300 3725);
DISPLAY 0.617021 (-300 3725);
PAINT SKYBLUE (-300 3725);
FORCEPROP 2 LASTPIN (550 2150) $PN 23
J 0
(560 2160);
DISPLAY 0.617021 (560 2160);
PAINT ORANGE (560 2160);
FORCEPROP 2 LASTPIN (550 2100) $PN 27
J 0
(560 2110);
DISPLAY 0.617021 (560 2110);
PAINT ORANGE (560 2110);
FORCEPROP 2 LASTPIN (550 2400) $PN 1
J 0
(560 2410);
DISPLAY 0.617021 (560 2410);
PAINT ORANGE (560 2410);
FORCEPROP 2 LASTPIN (550 2450) $PN 2
J 0
(560 2460);
DISPLAY 0.617021 (560 2460);
PAINT ORANGE (560 2460);
FORCEPROP 2 LASTPIN (550 2500) $PN 4
J 0
(560 2510);
DISPLAY 0.617021 (560 2510);
PAINT ORANGE (560 2510);
FORCEPROP 2 LASTPIN (550 2300) $PN 41
J 0
(560 2310);
DISPLAY 0.617021 (560 2310);
PAINT ORANGE (560 2310);
FORCEPROP 2 LASTPIN (550 2550) $PN 24
J 0
(560 2560);
DISPLAY 0.617021 (560 2560);
PAINT ORANGE (560 2560);
FORCEPROP 2 LASTPIN (550 2600) $PN 28
J 0
(560 2610);
DISPLAY 0.617021 (560 2610);
PAINT ORANGE (560 2610);
FORCEPROP 2 LASTPIN (550 2700) $PN 13
J 0
(560 2710);
DISPLAY 0.617021 (560 2710);
PAINT ORANGE (560 2710);
FORCEPROP 2 LASTPIN (550 2750) $PN 14
J 0
(560 2760);
DISPLAY 0.617021 (560 2760);
PAINT ORANGE (560 2760);
FORCEPROP 2 LASTPIN (550 2800) $PN 18
J 0
(560 2810);
DISPLAY 0.617021 (560 2810);
PAINT ORANGE (560 2810);
FORCEPROP 2 LASTPIN (550 3000) $PN 5
J 0
(560 3010);
DISPLAY 0.617021 (560 3010);
PAINT ORANGE (560 3010);
FORCEPROP 2 LASTPIN (550 2850) $PN 31
J 0
(560 2860);
DISPLAY 0.617021 (560 2860);
PAINT ORANGE (560 2860);
FORCEPROP 2 LASTPIN (550 2900) $PN 32
J 0
(560 2910);
DISPLAY 0.617021 (560 2910);
PAINT ORANGE (560 2910);
FORCEPROP 2 LASTPIN (550 3050) $PN 3
J 0
(560 3060);
DISPLAY 0.617021 (560 3060);
PAINT ORANGE (560 3060);
FORCEPROP 2 LASTPIN (550 3450) $PN 12
J 0
(560 3460);
DISPLAY 0.617021 (560 3460);
PAINT ORANGE (560 3460);
FORCEPROP 2 LASTPIN (550 3150) $PN 17
J 0
(560 3160);
DISPLAY 0.617021 (560 3160);
PAINT ORANGE (560 3160);
FORCEPROP 2 LASTPIN (550 3250) $PN 11
J 0
(560 3260);
DISPLAY 0.617021 (560 3260);
PAINT ORANGE (560 3260);
FORCEPROP 2 LASTPIN (550 3600) $PN 9
J 0
(560 3610);
DISPLAY 0.617021 (560 3610);
PAINT ORANGE (560 3610);
FORCEPROP 2 LAST CDS_LOCATION EU3P1
J 0
(-300 3775);
PAINT WHITE (-300 3775);
DISPLAY INVISIBLE (-300 3775);
FORCEPROP 2 LAST SEC 1
J 0
(-300 3825);
DISPLAY 0.680851 (-300 3825);
PAINT MONO (-300 3825);
DISPLAY INVISIBLE (-300 3825);
FORCEPROP 2 LAST SEC_TYPE QFN
J 0
(-300 3825);
DISPLAY 1.021277 (-300 3825);
PAINT ORANGE (-300 3825);
DISPLAY INVISIBLE (-300 3825);
FORCEPROP 1 LAST PACK_TYPE QFN
J 0
(-300 3825);
PAINT SKYBLUE (-300 3825);
DISPLAY INVISIBLE (-300 3825);
FORCEPROP 2 LAST CDS_LIB mstr_controller
J 0
(100 2850);
PAINT ORANGE (100 2850);
DISPLAY INVISIBLE (100 2850);
FORCEPROP 1 LAST CDS_LMAN_SYM_OUTLINE -400,850,400,-850
J 0
(100 2850);
DISPLAY 0.468085 (100 2850);
PAINT GREEN (100 2850);
DISPLAY INVISIBLE (100 2850);
FORCEPROP 1 LAST PATH I93
J 0
(200 3726);
PAINT WHITE (200 3726);
DISPLAY INVISIBLE (200 3726);
FORCEADD DNS..2
(-2120 4520);
PAINT RED (-2120 4520);
FORCEPROP 2 LAST CDS_LIB mstr_misc
J 0
(-2120 4520);
PAINT ORANGE (-2120 4520);
DISPLAY INVISIBLE (-2120 4520);
FORCEPROP 1 LAST COMMENT_BODY TRUE
R 1
J 0
(-2045 4295);
DISPLAY 0.872340 (-2045 4295);
PAINT GREEN (-2045 4295);
DISPLAY INVISIBLE (-2045 4295);
FORCEADD INTEL_CORP_BPAGE..1
(4250 200);
FORCEPROP 1 LAST CDS_CON_LAST_MODIFIED Tue Dec 01 11:52:24 2015
J 0
(2825 525);
PAINT ORANGE (2825 525);
DISPLAY INVISIBLE (2825 525);
FORCEPROP 1 LAST CUSTOM_TXT_CDS <CURRENT_DESIGN_SHEET> OF <TOTAL_DESIGN_SHEETS>
J 0
(3750 225);
PAINT GREEN (3750 225);
FORCEPROP 1 LAST CUSTOM_TXT_CDS <CON_LAST_MODIFIED>
J 0
(2325 550);
PAINT GREEN (2325 550);
FORCEPROP 2 LAST CUSTOM_TXT_CDS <XR_PAGE_TITLE>
J 0
(-3640 5450);
DISPLAY 0.638298 (-3640 5450);
PAINT PINK (-3640 5450);
DISPLAY INVISIBLE (-3640 5450);
FORCEPROP 1 LAST SCH_TITLE PVCCIO CPU0 (1 OF 2)
J 0
(-3700 250);
DISPLAY 1.212766 (-3700 250);
PAINT ORANGE (-3700 250);
FORCEPROP 1 LAST SCH_ADDRESS2 P.O. BOX 58119
J 0
(275 275);
DISPLAY 0.617021 (275 275);
PAINT GREEN (275 275);
FORCEPROP 1 LAST SCH_ADDRESS3 Santa Clara, CA 95052-8119
J 0
(275 225);
DISPLAY 0.617021 (275 225);
PAINT GREEN (275 225);
FORCEPROP 1 LAST SCH_ADDRESS1 2200 Mission College Blvd.
J 0
(275 325);
DISPLAY 0.617021 (275 325);
PAINT GREEN (275 325);
FORCEPROP 1 LAST SCH_NUMBER H4694802
J 0
(2950 350);
DISPLAY 1.212766 (2950 350);
PAINT YELLOW (2950 350);
FORCEPROP 1 LAST SCH_DEPT BESD
J 1
(-200 300);
DISPLAY 1.212766 (-200 300);
PAINT YELLOW (-200 300);
FORCEPROP 1 LAST SCH_REV 2.420
J 0
(4000 350);
DISPLAY 0.978723 (4000 350);
PAINT YELLOW (4000 350);
FORCEPROP 2 LAST PAGE_BORDER TRUE
J 0
(-3640 5450);
DISPLAY 0.638298 (-3640 5450);
PAINT PINK (-3640 5450);
DISPLAY INVISIBLE (-3640 5450);
FORCEPROP 2 LAST CDS_LIB mstr_symbols
J 0
(4250 200);
PAINT MONO (4250 200);
DISPLAY INVISIBLE (4250 200);
FORCEPROP 1 LAST COMMENT_BODY TRUE
J 0
(4262 212);
DISPLAY 0.468085 (4262 212);
PAINT GREEN (4262 212);
DISPLAY INVISIBLE (4262 212);
FORCEPROP 2 LAST CDS_XR_PAGE_TITLE CR-211 : @BASEBOARD_FAB2_LIB.BASEBOARD_FAB2(SCH_1):PAGE211
J 0
(-3640 5450);
DISPLAY 0.638298 (-3640 5450);
PAINT PINK (-3640 5450);
DISPLAY INVISIBLE (-3640 5450);
FORCEADD DNS..2
(-1670 4495);
PAINT RED (-1670 4495);
FORCEPROP 2 LAST CDS_LIB mstr_misc
J 0
(-1670 4495);
PAINT ORANGE (-1670 4495);
DISPLAY INVISIBLE (-1670 4495);
FORCEPROP 1 LAST COMMENT_BODY TRUE
R 1
J 0
(-1595 4270);
DISPLAY 0.872340 (-1595 4270);
PAINT GREEN (-1595 4270);
DISPLAY INVISIBLE (-1595 4270);
FORCEADD DNS..2
(-1120 4295);
PAINT RED (-1120 4295);
FORCEPROP 2 LAST CDS_LIB mstr_misc
J 0
(-1120 4295);
PAINT ORANGE (-1120 4295);
DISPLAY INVISIBLE (-1120 4295);
FORCEPROP 1 LAST COMMENT_BODY TRUE
R 1
J 0
(-1045 4070);
DISPLAY 0.872340 (-1045 4070);
PAINT GREEN (-1045 4070);
DISPLAY INVISIBLE (-1045 4070);
FORCEADD DESIGN_NOTE..1
(2775 5050);
FORCEPROP 0 LAST L1 SVID ADDRESS:  0X2
J 0
(2575 4925);
DISPLAY 1.021277 (2575 4925);
PAINT ORANGE (2575 4925);
FORCEPROP 2 LAST CDS_LIB mstr_symbols
J 0
(2775 5050);
PAINT ORANGE (2775 5050);
DISPLAY INVISIBLE (2775 5050);
FORCEPROP 1 LAST COMMENT_BODY TRUE
J 0
(2800 5150);
DISPLAY 0.978723 (2800 5150);
PAINT ORANGE (2800 5150);
DISPLAY INVISIBLE (2800 5150);
FORCEADD DESIGN_NOTE..1
(-300 1750);
FORCEPROP 0 LAST L1 SMBUS ADDRESS:  0X94
J 0
(-500 1625);
DISPLAY 1.021277 (-500 1625);
PAINT ORANGE (-500 1625);
FORCEPROP 2 LAST CDS_LIB mstr_symbols
J 0
(-300 1750);
PAINT ORANGE (-300 1750);
DISPLAY INVISIBLE (-300 1750);
FORCEPROP 1 LAST COMMENT_BODY TRUE
J 0
(-275 1850);
DISPLAY 0.978723 (-275 1850);
PAINT ORANGE (-275 1850);
DISPLAY INVISIBLE (-275 1850);
FORCEADD DNS..2
(1530 4095);
PAINT RED (1530 4095);
FORCEPROP 2 LAST CDS_LIB mstr_misc
J 0
(1530 4095);
PAINT ORANGE (1530 4095);
DISPLAY INVISIBLE (1530 4095);
FORCEPROP 1 LAST COMMENT_BODY TRUE
R 1
J 0
(1605 3870);
DISPLAY 0.872340 (1605 3870);
PAINT GREEN (1605 3870);
DISPLAY INVISIBLE (1605 3870);
WIRE 16 -1 (2475 1150)(2475 1325);
WIRE 16 -1 (2075 1275)(2075 1325);
WIRE 16 -1 (-1675 4600)(-1675 4775);
WIRE 16 -1 (550 2300)(925 2300);
WIRE 16 -1 (925 2300)(925 2150);
WIRE 16 -1 (550 2150)(925 2150);
WIRE 16 -1 (925 2150)(925 2100);
WIRE 16 -1 (550 2100)(925 2100);
WIRE 16 -1 (925 2100)(925 1950);
WIRE 16 -1 (75 4025)(75 4075);
WIRE 16 -1 (-325 4025)(-325 4075);
WIRE 16 -1 (-1125 4400)(-1125 4725);
WIRE 16 -1 (-1125 4725)(-625 4725);
WIRE 16 -1 (-625 4625)(-625 4725);
WIRE 16 -1 (-625 4725)(-625 4800);
WIRE 16 -1 (-2125 4625)(-2125 4825);
WIRE 16 -1 (-2500 4750)(-2500 4800);
WIRE 16 -1 (-2500 4150)(-2500 4200);
WIRE 16 -1 (-2725 4125)(-2725 4175);
WIRE 16 -1 (-350 2150)(-1025 2150);
WIRE 16 -1 (-1025 2100)(-1025 2150);
WIRE 16 -1 (-575 1275)(-575 1050);
WIRE 16 -1 (-575 1050)(-925 1050);
WIRE 16 -1 (-925 1250)(-925 1050);
WIRE 16 -1 (-925 1050)(-925 825);
WIRE 16 -1 (775 4200)(775 4525);
WIRE 16 -1 (775 4525)(1525 4525);
WIRE 16 -1 (1525 4200)(1525 4525);
WIRE 16 -1 (1525 4525)(1800 4525);
WIRE 16 -1 (1800 4525)(2075 4525);
WIRE 16 -1 (1800 4525)(1800 4725);
WIRE 16 -1 (2075 4525)(2075 4150);
WIRE 16 -1 (1650 2650)(1650 2525);
WIRE 16 -1 (-2700 2950)(-1675 2950);
FORCEPROP 2 LAST SIG_NAME SVID_DIO0_CPU0_R
J 0
(-2675 2960);
DISPLAY 0.617021 (-2675 2960);
PAINT ORANGE (-2675 2960);
WIRE 16 -1 (-1675 4400)(-1675 2950);
WIRE 16 -1 (-1675 2950)(-1350 2950);
WIRE 16 -1 (75 4275)(75 4325);
WIRE 16 -1 (75 4325)(-325 4325);
WIRE 16 -1 (-325 4275)(-325 4325);
WIRE 16 -1 (-325 4325)(-625 4325);
WIRE 16 -1 (-625 4325)(-625 4425);
WIRE 16 -1 (-625 3600)(-625 4325);
FORCEPROP 2 LAST SIG_NAME VR_PVCCIO_CPU0_VDD
R 1
J 0
(-640 3715);
DISPLAY 0.617021 (-640 3715);
PAINT ORANGE (-640 3715);
FORCEPROP 2 LASTPROP $XRERR UNIQUE?
J 0
(-880 3715);
DISPLAY 0.638298 (-880 3715);
PAINT MONO (-880 3715);
DISPLAY INVISIBLE (-880 3715);
WIRE 16 -1 (-350 3600)(-625 3600);
WIRE 16 -1 (2075 3250)(2075 3950);
WIRE 16 -1 (550 3250)(2075 3250);
FORCEPROP 2 LAST SIG_NAME IRQ_PVCCIO_CPU0_VRHOT_N
J 0
(650 3265);
DISPLAY 0.617021 (650 3265);
PAINT ORANGE (650 3265);
FORCEPROP 2 LASTPROP $XRERR UNIQUE?
J 0
(410 3265);
DISPLAY 0.638298 (410 3265);
PAINT MONO (410 3265);
DISPLAY INVISIBLE (410 3265);
WIRE 16 -1 (2475 1600)(2975 1600);
WIRE 16 -1 (2475 1600)(2075 1600);
FORCEPROP 2 LAST SIG_NAME VR_PVCCIO_CPU0_VD12
J 0
(2160 1615);
DISPLAY 0.617021 (2160 1615);
PAINT ORANGE (2160 1615);
WIRE 16 -1 (2475 1525)(2475 1600);
WIRE 16 -1 (2075 1525)(2075 1600);
WIRE 16 -1 (2650 3000)(550 3000);
FORCEPROP 0 LAST VOLTAGE 3.3
J 0
(2075 3075);
DISPLAY 1.021277 (2075 3075);
PAINT SKYBLUE (2075 3075);
DISPLAY INVISIBLE (2075 3075);
FORCEPROP 2 LAST SIG_NAME VR_PVCCIO_CPU0_PWM1
J 0
(2075 3015);
DISPLAY 0.617021 (2075 3015);
PAINT ORANGE (2075 3015);
WIRE 16 -1 (1975 3600)(2650 3600);
FORCEPROP 2 LAST SIG_NAME PWRGD_PVCCIO_CPU0
J 0
(2175 3615);
DISPLAY 0.617021 (2175 3615);
PAINT ORANGE (2175 3615);
WIRE 16 -1 (1400 3150)(2650 3150);
FORCEPROP 2 LAST SIG_NAME SVID_ALERT0_CPU0_R_N
J 0
(2075 3160);
DISPLAY 0.617021 (2075 3160);
PAINT ORANGE (2075 3160);
WIRE 16 -1 (1650 2850)(1650 3600);
WIRE 16 -1 (1650 3600)(1775 3600);
WIRE 16 -1 (1650 3600)(775 3600);
FORCEPROP 2 LAST SIG_NAME PWRGD_PVCCIO_CPU0_R
J 0
(910 3615);
DISPLAY 0.617021 (910 3615);
PAINT ORANGE (910 3615);
FORCEPROP 2 LASTPROP $XRERR UNIQUE?
J 0
(670 3615);
DISPLAY 0.638298 (670 3615);
PAINT MONO (670 3615);
DISPLAY INVISIBLE (670 3615);
WIRE 16 -1 (775 4000)(775 3600);
WIRE 16 -1 (550 3600)(775 3600);
WIRE 16 -1 (1525 4000)(1525 2900);
WIRE 16 -1 (550 2900)(1525 2900);
FORCEPROP 2 LAST SIG_NAME PU_VR_PVCCIO_CPU0_FAULT1
J 0
(650 2915);
DISPLAY 0.617021 (650 2915);
PAINT ORANGE (650 2915);
FORCEPROP 2 LASTPROP $XRERR UNIQUE?
J 0
(410 2915);
DISPLAY 0.638298 (410 2915);
PAINT MONO (410 2915);
DISPLAY INVISIBLE (410 2915);
WIRE 16 -1 (550 2750)(1150 2750);
FORCEPROP 2 LAST SIG_NAME TP_VR_PVCCIO_CPU0_MP1
J 0
(650 2765);
DISPLAY 0.617021 (650 2765);
PAINT ORANGE (650 2765);
FORCEPROP 2 LASTPROP $XRERR UNIQUE?
J 0
(1180 2750);
DISPLAY 0.638298 (1180 2750);
PAINT MONO (1180 2750);
DISPLAY INVISIBLE (1180 2750);
WIRE 16 -1 (550 2850)(1175 2850);
FORCEPROP 2 LAST SIG_NAME TP_VR_PVCCIO_CPU0_MP3
J 0
(650 2865);
DISPLAY 0.617021 (650 2865);
PAINT ORANGE (650 2865);
FORCEPROP 2 LASTPROP $XRERR UNIQUE?
J 0
(1205 2850);
DISPLAY 0.638298 (1205 2850);
PAINT MONO (1205 2850);
DISPLAY INVISIBLE (1205 2850);
WIRE 16 -1 (550 2700)(1175 2700);
FORCEPROP 2 LAST SIG_NAME TP_VR_PVCCIO_CPU0_MP0
J 0
(650 2715);
DISPLAY 0.617021 (650 2715);
PAINT ORANGE (650 2715);
FORCEPROP 2 LASTPROP $XRERR UNIQUE?
J 0
(1205 2700);
DISPLAY 0.638298 (1205 2700);
PAINT MONO (1205 2700);
DISPLAY INVISIBLE (1205 2700);
WIRE 16 -1 (550 2800)(1175 2800);
FORCEPROP 2 LAST SIG_NAME TP_VR_PVCCIO_CPU0_MP2
J 0
(650 2815);
DISPLAY 0.617021 (650 2815);
PAINT ORANGE (650 2815);
FORCEPROP 2 LASTPROP $XRERR UNIQUE?
J 0
(1205 2800);
DISPLAY 0.638298 (1205 2800);
PAINT MONO (1205 2800);
DISPLAY INVISIBLE (1205 2800);
WIRE 16 -1 (550 2600)(1075 2600);
FORCEPROP 2 LAST SIG_NAME NC_PVCCIO_CPU0_DNC4
J 0
(650 2615);
DISPLAY 0.617021 (650 2615);
PAINT ORANGE (650 2615);
FORCEPROP 2 LASTPROP $XRERR UNIQUE?
J 0
(1105 2600);
DISPLAY 0.638298 (1105 2600);
PAINT MONO (1105 2600);
DISPLAY INVISIBLE (1105 2600);
WIRE 16 -1 (550 2550)(1075 2550);
FORCEPROP 2 LAST SIG_NAME NC_PVCCIO_CPU0_DNC3
J 0
(650 2565);
DISPLAY 0.617021 (650 2565);
PAINT ORANGE (650 2565);
FORCEPROP 2 LASTPROP $XRERR UNIQUE?
J 0
(1105 2550);
DISPLAY 0.638298 (1105 2550);
PAINT MONO (1105 2550);
DISPLAY INVISIBLE (1105 2550);
WIRE 16 -1 (550 2500)(1075 2500);
FORCEPROP 2 LAST SIG_NAME NC_PVCCIO_CPU0_DNC2
J 0
(650 2515);
DISPLAY 0.617021 (650 2515);
PAINT ORANGE (650 2515);
FORCEPROP 2 LASTPROP $XRERR UNIQUE?
J 0
(1105 2500);
DISPLAY 0.638298 (1105 2500);
PAINT MONO (1105 2500);
DISPLAY INVISIBLE (1105 2500);
WIRE 16 -1 (550 2450)(1075 2450);
FORCEPROP 2 LAST SIG_NAME NC_PVCCIO_CPU0_DNC1
J 0
(650 2465);
DISPLAY 0.617021 (650 2465);
PAINT ORANGE (650 2465);
FORCEPROP 2 LASTPROP $XRERR UNIQUE?
J 0
(1105 2450);
DISPLAY 0.638298 (1105 2450);
PAINT MONO (1105 2450);
DISPLAY INVISIBLE (1105 2450);
WIRE 16 -1 (550 2400)(1075 2400);
FORCEPROP 2 LAST SIG_NAME NC_PVCCIO_CPU0_DNC0
J 0
(650 2415);
DISPLAY 0.617021 (650 2415);
PAINT ORANGE (650 2415);
FORCEPROP 2 LASTPROP $XRERR UNIQUE?
J 0
(1105 2400);
DISPLAY 0.638298 (1105 2400);
PAINT MONO (1105 2400);
DISPLAY INVISIBLE (1105 2400);
WIRE 16 -1 (1075 3050)(550 3050);
FORCEPROP 2 LAST SIG_NAME TP_PVCCIO_CPU0_BPWM1
J 0
(650 3065);
DISPLAY 0.617021 (650 3065);
PAINT ORANGE (650 3065);
FORCEPROP 2 LASTPROP $XRERR UNIQUE?
J 0
(1105 3050);
DISPLAY 0.638298 (1105 3050);
PAINT MONO (1105 3050);
DISPLAY INVISIBLE (1105 3050);
WIRE 16 -1 (550 3450)(1250 3450);
FORCEPROP 2 LAST SIG_NAME TP_PVCCIO_CPU0_PINALRT_N
J 0
(650 3465);
DISPLAY 0.617021 (650 3465);
PAINT ORANGE (650 3465);
FORCEPROP 2 LASTPROP $XRERR UNIQUE?
J 0
(1280 3450);
DISPLAY 0.638298 (1280 3450);
PAINT MONO (1280 3450);
DISPLAY INVISIBLE (1280 3450);
WIRE 16 -1 (1200 3150)(550 3150);
FORCEPROP 2 LAST SIG_NAME SVID_ALERT_PVCCIO_CPU0
J 0
(650 3165);
DISPLAY 0.617021 (650 3165);
PAINT ORANGE (650 3165);
FORCEPROP 2 LASTPROP $XRERR UNIQUE?
J 0
(410 3165);
DISPLAY 0.638298 (410 3165);
PAINT MONO (410 3165);
DISPLAY INVISIBLE (410 3165);
WIRE 16 -1 (-2500 4500)(-2500 4550);
WIRE 16 -1 (-2500 4400)(-2500 4500);
WIRE 16 -1 (-2500 4500)(-2725 4500);
FORCEPROP 0 LAST VOLTAGE 0.8
J 0
(-2600 4550);
DISPLAY 1.021277 (-2600 4550);
PAINT SKYBLUE (-2600 4550);
DISPLAY INVISIBLE (-2600 4550);
WIRE 16 -1 (-2725 4375)(-2725 4500);
WIRE 16 -1 (-2725 4500)(-3275 4500);
FORCEPROP 2 LAST SIG_NAME VR_PVCCIO_CPU0_VINSEN
J 0
(-3290 4515);
DISPLAY 0.617021 (-3290 4515);
PAINT ORANGE (-3290 4515);
WIRE 16 -1 (-1125 4200)(-1125 3250);
WIRE 16 -1 (-1125 3250)(-350 3250);
WIRE 16 -1 (-1850 3250)(-1125 3250);
FORCEPROP 2 LAST SIG_NAME VR_PVCCIO_CPU0_EN
J 0
(-1550 3265);
DISPLAY 0.617021 (-1550 3265);
PAINT ORANGE (-1550 3265);
FORCEPROP 2 LASTPROP $XRERR UNIQUE?
J 0
(-1790 3265);
DISPLAY 0.638298 (-1790 3265);
PAINT MONO (-1790 3265);
DISPLAY INVISIBLE (-1790 3265);
WIRE 16 -1 (-2075 3975)(-2125 3975);
WIRE 16 -1 (-2125 4425)(-2125 3975);
WIRE 16 -1 (-2975 3975)(-2125 3975);
FORCEPROP 0 LAST SIG_NAME SVID_CLK0_CPU0_R
J 0
(-2925 3985);
DISPLAY 0.617021 (-2925 3985);
PAINT ORANGE (-2925 3985);
WIRE 16 -1 (-350 3550)(-925 3550);
WIRE 16 -1 (-925 3550)(-925 3975);
WIRE 16 -1 (-1875 3975)(-925 3975);
FORCEPROP 2 LAST SIG_NAME SVID_CLK_PVCCIO_CPU0
J 0
(-1615 3990);
DISPLAY 0.617021 (-1615 3990);
PAINT ORANGE (-1615 3990);
FORCEPROP 2 LASTPROP $XRERR UNIQUE?
J 0
(-1855 3990);
DISPLAY 0.638298 (-1855 3990);
PAINT MONO (-1855 3990);
DISPLAY INVISIBLE (-1855 3990);
WIRE 16 -1 (-925 2100)(-350 2100);
FORCEPROP 0 LAST VOLTAGE 3.3
J 0
(-625 2150);
DISPLAY 1.021277 (-625 2150);
PAINT SKYBLUE (-625 2150);
DISPLAY INVISIBLE (-625 2150);
WIRE 16 -1 (-925 1450)(-925 2100);
FORCEPROP 0 LAST SIG_NAME VR_PVCCIO_CPU0_XADDR1
R 1
J 0
(-935 1460);
DISPLAY 0.617021 (-935 1460);
PAINT ORANGE (-935 1460);
FORCEPROP 2 LASTPROP $XRERR UNIQUE?
J 0
(-1175 1460);
DISPLAY 0.638298 (-1175 1460);
PAINT MONO (-1175 1460);
DISPLAY INVISIBLE (-1175 1460);
WIRE 16 -1 (-575 2050)(-350 2050);
WIRE 16 -1 (-575 1475)(-575 2050);
FORCEPROP 0 LAST VOLTAGE 3.3V
J 0
(-575 1525);
DISPLAY 1.021277 (-575 1525);
PAINT SKYBLUE (-575 1525);
DISPLAY INVISIBLE (-575 1525);
FORCEPROP 0 LAST SIG_NAME VR_PVCCIO_CPU0_XADDR2
R 1
J 0
(-585 1460);
DISPLAY 0.617021 (-585 1460);
PAINT ORANGE (-585 1460);
FORCEPROP 2 LASTPROP $XRERR UNIQUE?
J 0
(-825 1460);
DISPLAY 0.638298 (-825 1460);
PAINT MONO (-825 1460);
DISPLAY INVISIBLE (-825 1460);
WIRE 16 -1 (-1025 2800)(-350 2800);
FORCEPROP 2 LAST SIG_NAME TP_PVCCIO_CPU0_RESET_N
J 0
(-1025 2815);
DISPLAY 0.617021 (-1025 2815);
PAINT ORANGE (-1025 2815);
FORCEPROP 2 LASTPROP $XRERR UNIQUE?
J 0
(-1265 2800);
DISPLAY 0.638298 (-1265 2800);
PAINT MONO (-1265 2800);
DISPLAY INVISIBLE (-1265 2800);
WIRE 16 -1 (-1150 2450)(-350 2450);
FORCEPROP 2 LAST SIG_NAME SMB_VR_SDA_PVCCIO_CPU0
J 0
(-1050 2465);
DISPLAY 0.617021 (-1050 2465);
PAINT ORANGE (-1050 2465);
FORCEPROP 2 LASTPROP $XRERR UNIQUE?
J 0
(-1290 2465);
DISPLAY 0.638298 (-1290 2465);
PAINT MONO (-1290 2465);
DISPLAY INVISIBLE (-1290 2465);
WIRE 16 -1 (-1475 2400)(-350 2400);
FORCEPROP 2 LAST SIG_NAME SMB_VR_SCL_PVCCIO_CPU0
J 0
(-1050 2415);
DISPLAY 0.617021 (-1050 2415);
PAINT ORANGE (-1050 2415);
FORCEPROP 2 LASTPROP $XRERR UNIQUE?
J 0
(-1290 2415);
DISPLAY 0.638298 (-1290 2415);
PAINT MONO (-1290 2415);
DISPLAY INVISIBLE (-1290 2415);
WIRE 16 -1 (-1150 2950)(-350 2950);
FORCEPROP 2 LAST SIG_NAME SVID_VDIO_PVCCIO_CPU0
J 0
(-1050 2965);
DISPLAY 0.617021 (-1050 2965);
PAINT ORANGE (-1050 2965);
FORCEPROP 2 LASTPROP $XRERR UNIQUE?
J 0
(-1290 2965);
DISPLAY 0.638298 (-1290 2965);
PAINT MONO (-1290 2965);
DISPLAY INVISIBLE (-1290 2965);
WIRE 16 -1 (-1025 2300)(-350 2300);
FORCEPROP 2 LAST SIG_NAME TP_PVCCIO_CPU0_BTSEN
J 0
(-1000 2315);
DISPLAY 0.617021 (-1000 2315);
PAINT ORANGE (-1000 2315);
FORCEPROP 2 LASTPROP $XRERR UNIQUE?
J 0
(-1265 2300);
DISPLAY 0.638298 (-1265 2300);
PAINT MONO (-1265 2300);
DISPLAY INVISIBLE (-1265 2300);
WIRE 16 -1 (-1025 2200)(-350 2200);
FORCEPROP 2 LAST SIG_NAME TP_PVCCIO_CPU0_BIREF1
J 0
(-1000 2215);
DISPLAY 0.617021 (-1000 2215);
PAINT ORANGE (-1000 2215);
FORCEPROP 2 LASTPROP $XRERR UNIQUE?
J 0
(-1265 2200);
DISPLAY 0.638298 (-1265 2200);
PAINT MONO (-1265 2200);
DISPLAY INVISIBLE (-1265 2200);
WIRE 16 -1 (-1050 2600)(-350 2600);
FORCEPROP 2 LAST SIG_NAME TP_PVCCIO_CPU0_BVSEN
J 0
(-950 2615);
DISPLAY 0.617021 (-950 2615);
PAINT ORANGE (-950 2615);
FORCEPROP 2 LASTPROP $XRERR UNIQUE?
J 0
(-1290 2600);
DISPLAY 0.638298 (-1290 2600);
PAINT MONO (-1290 2600);
DISPLAY INVISIBLE (-1290 2600);
WIRE 16 -1 (-1050 2550)(-350 2550);
FORCEPROP 2 LAST SIG_NAME TP_PVCCIO_CPU0_BVREF
J 0
(-950 2565);
DISPLAY 0.617021 (-950 2565);
PAINT ORANGE (-950 2565);
FORCEPROP 2 LASTPROP $XRERR UNIQUE?
J 0
(-1290 2550);
DISPLAY 0.638298 (-1290 2550);
PAINT MONO (-1290 2550);
DISPLAY INVISIBLE (-1290 2550);
WIRE 16 -1 (-350 3100)(-1275 3100);
FORCEPROP 2 LAST SIG_NAME TP_VR_PVCCIO_CPU0_AIINSEN
J 0
(-1275 3110);
DISPLAY 0.617021 (-1275 3110);
PAINT ORANGE (-1275 3110);
FORCEPROP 2 LASTPROP $XRERR UNIQUE?
J 0
(-1515 3100);
DISPLAY 0.638298 (-1515 3100);
PAINT MONO (-1515 3100);
DISPLAY INVISIBLE (-1515 3100);
WIRE 16 -1 (-350 2650)(-2050 2650);
WIRE 16 -1 (-2050 1650)(-2050 2650);
WIRE 16 -1 (-2400 1650)(-2050 1650);
WIRE 16 -1 (-2400 1750)(-2400 1650);
WIRE 16 -1 (-3300 1650)(-2400 1650);
FORCEPROP 2 LAST SIG_NAME VSENSE_PVCCIO_CPU0_AVSN
J 0
(-3315 1665);
DISPLAY 0.617021 (-3315 1665);
PAINT ORANGE (-3315 1665);
WIRE 16 -1 (-350 2700)(-2125 2700);
FORCEPROP 0 LAST VOLTAGE 2
J 0
(-1300 2750);
DISPLAY 1.021277 (-1300 2750);
PAINT SKYBLUE (-1300 2750);
DISPLAY INVISIBLE (-1300 2750);
WIRE 16 -1 (-2125 2050)(-2125 2700);
WIRE 16 -1 (-2400 2050)(-2125 2050);
WIRE 16 -1 (-2500 2050)(-2400 2050);
FORCEPROP 2 LAST SIG_NAME VR_PVCCIO_CPU0_AVSP
J 0
(-2065 2715);
DISPLAY 0.617021 (-2065 2715);
PAINT ORANGE (-2065 2715);
FORCEPROP 2 LASTPROP $XRERR UNIQUE?
J 0
(-2305 2715);
DISPLAY 0.638298 (-2305 2715);
PAINT MONO (-2305 2715);
DISPLAY INVISIBLE (-2305 2715);
WIRE 16 -1 (-2400 1950)(-2400 2050);
WIRE 16 -1 (-350 3450)(-2150 3450);
WIRE 16 -1 (-2150 3750)(-2150 3450);
WIRE 16 -1 (-2150 3450)(-2700 3450);
FORCEPROP 2 LAST SIG_NAME VR_PVCCIO_CPU0_AIREF1
J 0
(-2700 3465);
DISPLAY 0.617021 (-2700 3465);
PAINT ORANGE (-2700 3465);
WIRE 16 -1 (-2350 3750)(-2150 3750);
WIRE 16 -1 (-350 3000)(-2700 3000);
FORCEPROP 2 LAST SIG_NAME VR_PVCCIO_CPU0_VD12
J 0
(-2700 3015);
DISPLAY 0.617021 (-2700 3015);
PAINT ORANGE (-2700 3015);
WIRE 16 -1 (-350 3150)(-2700 3150);
FORCEPROP 2 LAST SIG_NAME VR_PVCCIO_CPU0_VINSEN
J 0
(-2725 3165);
DISPLAY 0.617021 (-2725 3165);
PAINT ORANGE (-2725 3165);
WIRE 16 -1 (-2700 3400)(-350 3400);
FORCEPROP 2 LAST SIG_NAME ISENSE_PVCCIO_CPU0_PH1_IMON
J 2
(-2079 3400);
DISPLAY 0.617021 (-2079 3400);
PAINT ORANGE (-2079 3400);
WIRE 16 -1 (-2700 3300)(-350 3300);
FORCEPROP 0 LAST VOLTAGE 3.6
J 0
(-2725 3375);
DISPLAY 1.021277 (-2725 3375);
PAINT SKYBLUE (-2725 3375);
DISPLAY INVISIBLE (-2725 3375);
FORCEPROP 2 LAST SIG_NAME A_TSENSE_PVCCIO_CPU0
J 2
(-2208 3316);
DISPLAY 0.617021 (-2208 3316);
PAINT ORANGE (-2208 3316);
WIRE 16 -1 (-2700 2400)(-1675 2400);
FORCEPROP 2 LAST SIG_NAME SMB_VR_STBY_LVC3_SCL
J 0
(-2725 2415);
DISPLAY 0.617021 (-2725 2415);
PAINT ORANGE (-2725 2415);
WIRE 16 -1 (-2700 2450)(-1350 2450);
FORCEPROP 2 LAST SIG_NAME SMB_VR_STBY_LVC3_SDA
J 0
(-2725 2465);
DISPLAY 0.617021 (-2725 2465);
PAINT ORANGE (-2725 2465);
WIRE 16 -1 (-2700 3250)(-2050 3250);
FORCEPROP 2 LAST SIG_NAME FM_PVCCIO_CPU0_EN
J 0
(-2700 3265);
DISPLAY 0.617021 (-2700 3265);
PAINT ORANGE (-2700 3265);
WIRE 16 -1 (-2700 2050)(-3375 2050);
FORCEPROP 2 LAST SIG_NAME VSENSE_PVCCIO_CPU0_AVSP
J 0
(-3365 2065);
DISPLAY 0.617021 (-3365 2065);
PAINT ORANGE (-3365 2065);
WIRE 16 -1 (-2550 3750)(-3225 3750);
FORCEPROP 2 LAST SIG_NAME VR_PVCCIO_CPU0_VD12
J 0
(-3250 3765);
DISPLAY 0.617021 (-3250 3765);
PAINT ORANGE (-3250 3765);
DOT 1 (-2400 1650);
DOT 1 (-2400 2050);
DOT 1 (-2150 3450);
DOT 1 (-2125 3975);
DOT 1 (-925 1050);
DOT 1 (-1675 2950);
DOT 1 (-1125 3250);
DOT 1 (-2725 4500);
DOT 1 (-2500 4500);
DOT 1 (-625 4325);
DOT 1 (-625 4725);
DOT 1 (-325 4325);
DOT 1 (925 2100);
DOT 1 (925 2150);
DOT 1 (775 3600);
DOT 1 (1650 3600);
DOT 1 (2475 1600);
DOT 1 (1525 4525);
DOT 1 (1800 4525);
FORCENOTE
ROOM = PVCCIO_CPU0
(-3550 425) 0;
DISPLAY LEFT (-3550 425);
DISPLAY 1.021277 (-3550 425);
PAINT PURPLE (-3550 425);
FORCENOTE
BOM_COST = PROC_VRD_PVCCIO_CPU0
(-3550 350) 0;
DISPLAY LEFT (-3550 350);
DISPLAY 1.021277 (-3550 350);
PAINT PURPLE (-3550 350);
QUIT
